FILE_TYPE = MACRO_DRAWING;
SET COLOR_WIRE YELLOW;
SET COLOR_PROP ORANGE;
SET COLOR_DOT WHITE;
SET COLOR_ARC YELLOW;
SET COLOR_BODY GREEN;
SET COLOR_NOTE PURPLE;
SET PROP_DISPLAY VALUE;
SET PAGE_NUMBER P200;
FORCEADD OFFPAGE..1
(-7175 3875);
FORCEPROP 2 LAST $XR0 200 
J 0
(-7427 3875);
DISPLAY 0.638298 (-7427 3875);
PAINT MONO (-7427 3875);
FORCEPROP 2 LAST PATH I1
J 0
(-7125 3950);
DISPLAY 1.021277 (-7125 3950);
DISPLAY INVISIBLE (-7125 3950);
FORCEPROP 1 LAST COMMENT_BODY TRUE
J 0
(-7050 3775);
DISPLAY 0.872340 (-7050 3775);
PAINT GREEN (-7050 3775);
DISPLAY INVISIBLE (-7050 3775);
FORCEPROP 1 LAST OFFPAGE TRUE
J 0
(-6850 3750);
DISPLAY 0.872340 (-6850 3750);
PAINT GREEN (-6850 3750);
DISPLAY INVISIBLE (-6850 3750);
FORCEPROP 2 LAST CDS_LIB standard
J 2
(-7175 3875);
DISPLAY INVISIBLE (-7175 3875);
FORCEADD OFFPAGE..2
R 2
(-7225 4475);
FORCEPROP 2 LAST $XR0 200 
J 0
(-7480 4475);
DISPLAY 0.638298 (-7480 4475);
PAINT MONO (-7480 4475);
FORCEPROP 2 LAST CDS_LIB standard
J 2
(-7225 4475);
DISPLAY INVISIBLE (-7225 4475);
FORCEPROP 1 LAST COMMENT_BODY TRUE
J 2
(-7180 4380);
DISPLAY 0.872340 (-7180 4380);
PAINT GREEN (-7180 4380);
DISPLAY INVISIBLE (-7180 4380);
FORCEPROP 2 LAST PATH I10
J 0
(-7175 4550);
DISPLAY 1.021277 (-7175 4550);
DISPLAY INVISIBLE (-7175 4550);
FORCEPROP 1 LAST OFFPAGE TRUE
J 2
(-7550 4350);
DISPLAY 0.872340 (-7550 4350);
PAINT GREEN (-7550 4350);
DISPLAY INVISIBLE (-7550 4350);
FORCEADD Q_INDUCTOR..1
(-3350 4500);
FORCEPROP 1 LAST LOCATION PL54
J 0
(-3375 4550);
DISPLAY 0.489362 (-3375 4550);
PAINT SKYBLUE (-3375 4550);
FORCEPROP 0 LAST $SEC 1
J 0
(-3375 4575);
DISPLAY 0.680851 (-3375 4575);
PAINT MONO (-3375 4575);
DISPLAY INVISIBLE (-3375 4575);
FORCEPROP 0 LAST CDS_SEC 1
J 0
(-3375 4575);
DISPLAY 1.021277 (-3375 4575);
DISPLAY INVISIBLE (-3375 4575);
FORCEPROP 0 LASTPIN (-3450 4475) $PN 1
J 2
(-3460 4485);
DISPLAY 0.489362 (-3460 4485);
PAINT MONO (-3460 4485);
FORCEPROP 0 LASTPIN (-3250 4475) $PN 2
J 0
(-3240 4485);
DISPLAY 0.489362 (-3240 4485);
PAINT MONO (-3240 4485);
FORCEPROP 1 LAST MATERIAL IND
J 0
(-3450 4325);
DISPLAY 0.489362 (-3450 4325);
PAINT SKYBLUE (-3450 4325);
FORCEPROP 2 LAST VALUE 90NH/155AA
J 0
(-3450 4425);
DISPLAY 0.489362 (-3450 4425);
PAINT SKYBLUE (-3450 4425);
FORCEPROP 1 LAST PART_NUMBER CVA90^0KZ04
J 0
(-3450 4375);
DISPLAY 0.489362 (-3450 4375);
PAINT SKYBLUE (-3450 4375);
FORCEPROP 2 LAST PACK_TYPE SMLF
J 0
(-3450 4275);
DISPLAY 0.489362 (-3450 4275);
PAINT SKYBLUE (-3450 4275);
FORCEPROP 2 LAST CDS_LIB pure_quanta
J 0
(-3350 4500);
DISPLAY INVISIBLE (-3350 4500);
FORCEPROP 1 LAST NEEDS_NO_SIZE TRUE
J 0
(-3350 4500);
DISPLAY 0.468085 (-3350 4500);
PAINT GREEN (-3350 4500);
DISPLAY INVISIBLE (-3350 4500);
FORCEPROP 1 LAST PATH I101
J 0
(-3275 4555);
DISPLAY 0.723404 (-3275 4555);
PAINT GREEN (-3275 4555);
DISPLAY INVISIBLE (-3275 4555);
FORCEADD VCC_CORE..1
(-3900 5650);
FORCEPROP 3 LASTPIN (-3900 5600) SIG_NAME SW_P12V_STBY_PVDD11_S3_P1_FLT\g
J 0
(-3890 5610);
DISPLAY 0.659574 (-3890 5610);
PAINT MONO (-3890 5610);
DISPLAY INVISIBLE (-3890 5610);
FORCEPROP 1 LAST HDL_POWER SW_P12V_STBY_PVDD11_S3_P1_FLT
J 1
(-3900 5700);
DISPLAY 0.489362 (-3900 5700);
PAINT GREEN (-3900 5700);
FORCEPROP 2 LAST CDS_LIB pure_quanta_power
J 0
(-3900 5650);
DISPLAY INVISIBLE (-3900 5650);
FORCEPROP 1 LAST PATH I104
J 0
(-3850 5675);
DISPLAY 0.872340 (-3850 5675);
PAINT AQUA (-3850 5675);
DISPLAY INVISIBLE (-3850 5675);
FORCEADD Q_INDUCTOR..1
(-3300 1575);
FORCEPROP 1 LAST LOCATION PL55
J 0
(-3325 1625);
DISPLAY 0.489362 (-3325 1625);
PAINT SKYBLUE (-3325 1625);
FORCEPROP 0 LAST $SEC 1
J 0
(-3325 1650);
DISPLAY 0.680851 (-3325 1650);
PAINT MONO (-3325 1650);
DISPLAY INVISIBLE (-3325 1650);
FORCEPROP 0 LAST CDS_SEC 1
J 0
(-3325 1650);
DISPLAY 1.021277 (-3325 1650);
DISPLAY INVISIBLE (-3325 1650);
FORCEPROP 0 LASTPIN (-3400 1550) $PN 1
J 2
(-3410 1560);
DISPLAY 0.489362 (-3410 1560);
PAINT MONO (-3410 1560);
FORCEPROP 0 LASTPIN (-3200 1550) $PN 2
J 0
(-3190 1560);
DISPLAY 0.489362 (-3190 1560);
PAINT MONO (-3190 1560);
FORCEPROP 1 LAST MATERIAL IND
J 0
(-3400 1400);
DISPLAY 0.489362 (-3400 1400);
PAINT SKYBLUE (-3400 1400);
FORCEPROP 2 LAST VALUE 90NH/155AA
J 0
(-3400 1500);
DISPLAY 0.489362 (-3400 1500);
PAINT SKYBLUE (-3400 1500);
FORCEPROP 1 LAST PART_NUMBER CVA90^0KZ04
J 0
(-3400 1450);
DISPLAY 0.489362 (-3400 1450);
PAINT SKYBLUE (-3400 1450);
FORCEPROP 2 LAST PACK_TYPE SMLF
J 0
(-3400 1350);
DISPLAY 0.489362 (-3400 1350);
PAINT SKYBLUE (-3400 1350);
FORCEPROP 1 LAST NEEDS_NO_SIZE TRUE
J 0
(-3300 1575);
DISPLAY 0.468085 (-3300 1575);
PAINT GREEN (-3300 1575);
DISPLAY INVISIBLE (-3300 1575);
FORCEPROP 2 LAST CDS_LIB pure_quanta
J 0
(-3300 1575);
DISPLAY INVISIBLE (-3300 1575);
FORCEPROP 1 LAST PATH I105
J 0
(-3225 1630);
DISPLAY 0.723404 (-3225 1630);
PAINT GREEN (-3225 1630);
DISPLAY INVISIBLE (-3225 1630);
FORCEADD Q_CAP..1
(-4075 2450);
FORCEPROP 1 LAST LOCATION PC518_2
J 0
(-4025 2550);
DISPLAY 0.489362 (-4025 2550);
PAINT SKYBLUE (-4025 2550);
FORCEPROP 0 LAST $SEC 1
J 0
(-4025 2575);
DISPLAY 0.680851 (-4025 2575);
PAINT MONO (-4025 2575);
DISPLAY INVISIBLE (-4025 2575);
FORCEPROP 0 LAST CDS_SEC 1
J 0
(-4025 2575);
DISPLAY 1.021277 (-4025 2575);
DISPLAY INVISIBLE (-4025 2575);
FORCEPROP 1 LASTPIN (-4075 2550) $PN 1
J 0
(-4065 2530);
DISPLAY 0.489362 (-4065 2530);
PAINT MONO (-4065 2530);
FORCEPROP 1 LASTPIN (-4075 2350) $PN 2
J 0
(-4065 2330);
DISPLAY 0.489362 (-4065 2330);
PAINT MONO (-4065 2330);
FORCEPROP 1 LAST MATERIAL X6S
J 0
(-4025 2350);
DISPLAY 0.489362 (-4025 2350);
PAINT SKYBLUE (-4025 2350);
FORCEPROP 1 LAST TOLERANCE 10%
J 0
(-4025 2400);
DISPLAY 0.489362 (-4025 2400);
PAINT SKYBLUE (-4025 2400);
FORCEPROP 1 LAST VALUE 10UF
J 0
(-4025 2500);
DISPLAY 0.489362 (-4025 2500);
PAINT SKYBLUE (-4025 2500);
FORCEPROP 1 LAST PART_NUMBER CH6104KEA00
J 0
(-4025 2300);
DISPLAY 0.489362 (-4025 2300);
PAINT SKYBLUE (-4025 2300);
FORCEPROP 1 LAST VOLTAGE 25V
J 0
(-4025 2450);
DISPLAY 0.489362 (-4025 2450);
PAINT SKYBLUE (-4025 2450);
FORCEPROP 1 LAST PACK_TYPE C0805
J 0
(-4025 2250);
DISPLAY 0.489362 (-4025 2250);
PAINT SKYBLUE (-4025 2250);
FORCEPROP 2 LAST CDS_LIB pure_quanta
J 0
(-4075 2450);
DISPLAY INVISIBLE (-4075 2450);
FORCEPROP 1 LAST PATH I107
J 0
(-4025 2600);
DISPLAY 0.978723 (-4025 2600);
PAINT WHITE (-4025 2600);
DISPLAY INVISIBLE (-4025 2600);
FORCEADD Q_RES..1
(-3600 3350);
FORCEPROP 1 LAST LOCATION PR332
J 0
(-3650 3400);
DISPLAY 0.489362 (-3650 3400);
PAINT SKYBLUE (-3650 3400);
FORCEPROP 0 LAST $SEC 1
J 0
(-3650 3450);
DISPLAY 0.680851 (-3650 3450);
PAINT MONO (-3650 3450);
DISPLAY INVISIBLE (-3650 3450);
FORCEPROP 0 LAST CDS_SEC 1
J 0
(-3650 3450);
DISPLAY 1.021277 (-3650 3450);
DISPLAY INVISIBLE (-3650 3450);
FORCEPROP 1 LASTPIN (-3700 3350) $PN 1
J 0
(-3688 3362);
DISPLAY 0.489362 (-3688 3362);
PAINT MONO (-3688 3362);
FORCEPROP 1 LASTPIN (-3500 3350) $PN 2
J 0
(-3538 3362);
DISPLAY 0.489362 (-3538 3362);
PAINT MONO (-3538 3362);
FORCEPROP 1 LAST WATTAGE 1/16W
J 0
(-3500 3300);
DISPLAY 0.489362 (-3500 3300);
PAINT SKYBLUE (-3500 3300);
FORCEPROP 1 LAST MATERIAL CHIP
J 0
(-3850 3275);
DISPLAY 0.489362 (-3850 3275);
PAINT SKYBLUE (-3850 3275);
FORCEPROP 1 LAST TOLERANCE 5%
J 0
(-3475 3375);
DISPLAY 0.489362 (-3475 3375);
PAINT SKYBLUE (-3475 3375);
FORCEPROP 1 LAST VALUE 0
J 2
(-3725 3375);
DISPLAY 0.489362 (-3725 3375);
PAINT SKYBLUE (-3725 3375);
FORCEPROP 1 LAST PART_NUMBER CS00002JB38
J 0
(-3850 3300);
DISPLAY 0.489362 (-3850 3300);
PAINT SKYBLUE (-3850 3300);
FORCEPROP 1 LAST PACK_TYPE 0402LF
J 0
(-3500 3275);
DISPLAY 0.489362 (-3500 3275);
PAINT SKYBLUE (-3500 3275);
FORCEPROP 2 LAST CDS_LIB pure_quanta
J 0
(-3600 3350);
DISPLAY INVISIBLE (-3600 3350);
FORCEPROP 1 LAST PATH I110
J 0
(-3650 3500);
DISPLAY 0.978723 (-3650 3500);
PAINT WHITE (-3650 3500);
DISPLAY INVISIBLE (-3650 3500);
FORCEADD Q_RES..1
(-3525 550);
FORCEPROP 1 LAST LOCATION PR333
J 0
(-3575 600);
DISPLAY 0.489362 (-3575 600);
PAINT SKYBLUE (-3575 600);
FORCEPROP 0 LAST $SEC 1
J 0
(-3575 650);
DISPLAY 0.680851 (-3575 650);
PAINT MONO (-3575 650);
DISPLAY INVISIBLE (-3575 650);
FORCEPROP 0 LAST CDS_SEC 1
J 0
(-3575 650);
DISPLAY 1.021277 (-3575 650);
DISPLAY INVISIBLE (-3575 650);
FORCEPROP 1 LASTPIN (-3625 550) $PN 1
J 0
(-3613 562);
DISPLAY 0.489362 (-3613 562);
PAINT MONO (-3613 562);
FORCEPROP 1 LASTPIN (-3425 550) $PN 2
J 0
(-3463 562);
DISPLAY 0.489362 (-3463 562);
PAINT MONO (-3463 562);
FORCEPROP 1 LAST WATTAGE 1/16W
J 0
(-3425 500);
DISPLAY 0.489362 (-3425 500);
PAINT SKYBLUE (-3425 500);
FORCEPROP 1 LAST MATERIAL CHIP
J 0
(-3775 475);
DISPLAY 0.489362 (-3775 475);
PAINT SKYBLUE (-3775 475);
FORCEPROP 1 LAST TOLERANCE 5%
J 0
(-3400 575);
DISPLAY 0.489362 (-3400 575);
PAINT SKYBLUE (-3400 575);
FORCEPROP 1 LAST VALUE 0
J 2
(-3650 575);
DISPLAY 0.489362 (-3650 575);
PAINT SKYBLUE (-3650 575);
FORCEPROP 1 LAST PART_NUMBER CS00002JB38
J 0
(-3775 500);
DISPLAY 0.489362 (-3775 500);
PAINT SKYBLUE (-3775 500);
FORCEPROP 1 LAST PACK_TYPE 0402LF
J 0
(-3425 475);
DISPLAY 0.489362 (-3425 475);
PAINT SKYBLUE (-3425 475);
FORCEPROP 2 LAST CDS_LIB pure_quanta
J 0
(-3525 550);
DISPLAY INVISIBLE (-3525 550);
FORCEPROP 1 LAST PATH I111
J 0
(-3575 700);
DISPLAY 0.978723 (-3575 700);
PAINT WHITE (-3575 700);
DISPLAY INVISIBLE (-3575 700);
FORCEADD Q_CAPP..1
(-2575 2625);
FORCEPROP 1 LAST LOCATION PC528
J 0
(-2525 2725);
DISPLAY 0.489362 (-2525 2725);
PAINT SKYBLUE (-2525 2725);
FORCEPROP 0 LAST $SEC 1
J 0
(-2525 2775);
DISPLAY 0.680851 (-2525 2775);
PAINT MONO (-2525 2775);
DISPLAY INVISIBLE (-2525 2775);
FORCEPROP 0 LAST CDS_SEC 1
J 0
(-2525 2775);
DISPLAY 1.021277 (-2525 2775);
DISPLAY INVISIBLE (-2525 2775);
FORCEPROP 1 LASTPIN (-2575 2725) $PN 1
J 0
(-2565 2710);
DISPLAY 0.489362 (-2565 2710);
PAINT MONO (-2565 2710);
FORCEPROP 1 LASTPIN (-2575 2525) $PN 2
J 0
(-2565 2510);
DISPLAY 0.489362 (-2565 2510);
PAINT MONO (-2565 2510);
FORCEPROP 1 LAST MATERIAL SPCAP
J 0
(-2525 2525);
DISPLAY 0.489362 (-2525 2525);
PAINT SKYBLUE (-2525 2525);
FORCEPROP 1 LAST TOLERANCE 20%
J 0
(-2525 2625);
DISPLAY 0.489362 (-2525 2625);
PAINT SKYBLUE (-2525 2625);
FORCEPROP 1 LAST VALUE 470UF
J 0
(-2525 2675);
DISPLAY 0.489362 (-2525 2675);
PAINT SKYBLUE (-2525 2675);
FORCEPROP 1 LAST PART_NUMBER CH747LM8825
J 0
(-2525 2425);
DISPLAY 0.489362 (-2525 2425);
PAINT SKYBLUE (-2525 2425);
FORCEPROP 1 LAST VOLTAGE 2.5V
J 0
(-2525 2575);
DISPLAY 0.489362 (-2525 2575);
PAINT SKYBLUE (-2525 2575);
FORCEPROP 1 LAST PACK_TYPE SMLF
J 0
(-2525 2475);
DISPLAY 0.489362 (-2525 2475);
PAINT SKYBLUE (-2525 2475);
FORCEPROP 2 LAST CDS_LIB pure_quanta
J 0
(-2575 2625);
DISPLAY INVISIBLE (-2575 2625);
FORCEPROP 1 LAST PATH I118
J 0
(-2525 2775);
DISPLAY 0.978723 (-2525 2775);
DISPLAY INVISIBLE (-2525 2775);
FORCEADD Q_CAPP..1
(-1800 2650);
FORCEPROP 1 LAST LOCATION PC530
J 0
(-1750 2750);
DISPLAY 0.489362 (-1750 2750);
PAINT SKYBLUE (-1750 2750);
FORCEPROP 0 LAST $SEC 1
J 0
(-1750 2800);
DISPLAY 0.680851 (-1750 2800);
PAINT MONO (-1750 2800);
DISPLAY INVISIBLE (-1750 2800);
FORCEPROP 0 LAST CDS_SEC 1
J 0
(-1750 2800);
DISPLAY 1.021277 (-1750 2800);
DISPLAY INVISIBLE (-1750 2800);
FORCEPROP 1 LASTPIN (-1800 2750) $PN 1
J 0
(-1790 2735);
DISPLAY 0.489362 (-1790 2735);
PAINT MONO (-1790 2735);
FORCEPROP 1 LASTPIN (-1800 2550) $PN 2
J 0
(-1790 2535);
DISPLAY 0.489362 (-1790 2535);
PAINT MONO (-1790 2535);
FORCEPROP 1 LAST MATERIAL OSCON
J 0
(-1750 2550);
DISPLAY 0.489362 (-1750 2550);
PAINT SKYBLUE (-1750 2550);
FORCEPROP 1 LAST TOLERANCE 20%
J 0
(-1750 2650);
DISPLAY 0.489362 (-1750 2650);
PAINT SKYBLUE (-1750 2650);
FORCEPROP 1 LAST VALUE 390UF
J 0
(-1750 2700);
DISPLAY 0.489362 (-1750 2700);
PAINT SKYBLUE (-1750 2700);
FORCEPROP 1 LAST PART_NUMBER CC7390JMZ12
J 0
(-1750 2450);
DISPLAY 0.489362 (-1750 2450);
PAINT SKYBLUE (-1750 2450);
FORCEPROP 1 LAST VOLTAGE 2.5V
J 0
(-1750 2600);
DISPLAY 0.489362 (-1750 2600);
PAINT SKYBLUE (-1750 2600);
FORCEPROP 1 LAST PACK_TYPE SMLF
J 0
(-1750 2500);
DISPLAY 0.489362 (-1750 2500);
PAINT SKYBLUE (-1750 2500);
FORCEPROP 2 LAST CDS_LIB pure_quanta
J 0
(-1800 2650);
DISPLAY INVISIBLE (-1800 2650);
FORCEPROP 1 LAST PATH I119
J 0
(-1750 2800);
DISPLAY 0.978723 (-1750 2800);
DISPLAY INVISIBLE (-1750 2800);
FORCEADD Q_CAPP..1
(-1475 2650);
FORCEPROP 1 LAST LOCATION PC531
J 0
(-1425 2750);
DISPLAY 0.489362 (-1425 2750);
PAINT SKYBLUE (-1425 2750);
FORCEPROP 0 LAST $SEC 1
J 0
(-1425 2800);
DISPLAY 0.680851 (-1425 2800);
PAINT MONO (-1425 2800);
DISPLAY INVISIBLE (-1425 2800);
FORCEPROP 0 LAST CDS_SEC 1
J 0
(-1425 2800);
DISPLAY 1.021277 (-1425 2800);
DISPLAY INVISIBLE (-1425 2800);
FORCEPROP 1 LASTPIN (-1475 2750) $PN 1
J 0
(-1465 2735);
DISPLAY 0.489362 (-1465 2735);
PAINT MONO (-1465 2735);
FORCEPROP 1 LASTPIN (-1475 2550) $PN 2
J 0
(-1465 2535);
DISPLAY 0.489362 (-1465 2535);
PAINT MONO (-1465 2535);
FORCEPROP 1 LAST MATERIAL OSCON
J 0
(-1425 2550);
DISPLAY 0.489362 (-1425 2550);
PAINT SKYBLUE (-1425 2550);
FORCEPROP 1 LAST TOLERANCE 20%
J 0
(-1425 2650);
DISPLAY 0.489362 (-1425 2650);
PAINT SKYBLUE (-1425 2650);
FORCEPROP 1 LAST VALUE 390UF
J 0
(-1425 2700);
DISPLAY 0.489362 (-1425 2700);
PAINT SKYBLUE (-1425 2700);
FORCEPROP 1 LAST PART_NUMBER CC7390JMZ12
J 0
(-1425 2450);
DISPLAY 0.489362 (-1425 2450);
PAINT SKYBLUE (-1425 2450);
FORCEPROP 1 LAST VOLTAGE 2.5V
J 0
(-1425 2600);
DISPLAY 0.489362 (-1425 2600);
PAINT SKYBLUE (-1425 2600);
FORCEPROP 1 LAST PACK_TYPE SMLF
J 0
(-1425 2500);
DISPLAY 0.489362 (-1425 2500);
PAINT SKYBLUE (-1425 2500);
FORCEPROP 2 LAST CDS_LIB pure_quanta
J 0
(-1475 2650);
DISPLAY INVISIBLE (-1475 2650);
FORCEPROP 1 LAST PATH I120
J 0
(-1425 2800);
DISPLAY 0.978723 (-1425 2800);
DISPLAY INVISIBLE (-1425 2800);
FORCEADD Q_CAPP..1
(-1150 2650);
FORCEPROP 1 LAST LOCATION PC532
J 0
(-1100 2750);
DISPLAY 0.489362 (-1100 2750);
PAINT SKYBLUE (-1100 2750);
FORCEPROP 0 LAST $SEC 1
J 0
(-1100 2800);
DISPLAY 0.680851 (-1100 2800);
PAINT MONO (-1100 2800);
DISPLAY INVISIBLE (-1100 2800);
FORCEPROP 0 LAST CDS_SEC 1
J 0
(-1100 2800);
DISPLAY 1.021277 (-1100 2800);
DISPLAY INVISIBLE (-1100 2800);
FORCEPROP 1 LASTPIN (-1150 2750) $PN 1
J 0
(-1140 2735);
DISPLAY 0.489362 (-1140 2735);
PAINT MONO (-1140 2735);
FORCEPROP 1 LASTPIN (-1150 2550) $PN 2
J 0
(-1140 2535);
DISPLAY 0.489362 (-1140 2535);
PAINT MONO (-1140 2535);
FORCEPROP 1 LAST MATERIAL OSCON
J 0
(-1100 2550);
DISPLAY 0.489362 (-1100 2550);
PAINT SKYBLUE (-1100 2550);
FORCEPROP 1 LAST TOLERANCE 20%
J 0
(-1100 2650);
DISPLAY 0.489362 (-1100 2650);
PAINT SKYBLUE (-1100 2650);
FORCEPROP 1 LAST VALUE 390UF
J 0
(-1100 2700);
DISPLAY 0.489362 (-1100 2700);
PAINT SKYBLUE (-1100 2700);
FORCEPROP 1 LAST PART_NUMBER CC7390JMZ12
J 0
(-1100 2450);
DISPLAY 0.489362 (-1100 2450);
PAINT SKYBLUE (-1100 2450);
FORCEPROP 1 LAST VOLTAGE 2.5V
J 0
(-1100 2600);
DISPLAY 0.489362 (-1100 2600);
PAINT SKYBLUE (-1100 2600);
FORCEPROP 1 LAST PACK_TYPE SMLF
J 0
(-1100 2500);
DISPLAY 0.489362 (-1100 2500);
PAINT SKYBLUE (-1100 2500);
FORCEPROP 2 LAST CDS_LIB pure_quanta
J 0
(-1150 2650);
DISPLAY INVISIBLE (-1150 2650);
FORCEPROP 1 LAST PATH I121
J 0
(-1100 2800);
DISPLAY 0.978723 (-1100 2800);
DISPLAY INVISIBLE (-1100 2800);
FORCEADD VCC_CORE..1
(-1800 2875);
FORCEPROP 3 LASTPIN (-1800 2825) SIG_NAME PVDD11_S3_P1\g
J 0
(-1790 2835);
DISPLAY 0.659574 (-1790 2835);
PAINT MONO (-1790 2835);
DISPLAY INVISIBLE (-1790 2835);
FORCEPROP 1 LAST HDL_POWER PVDD11_S3_P1
J 1
(-1800 2925);
DISPLAY 0.489362 (-1800 2925);
PAINT GREEN (-1800 2925);
FORCEPROP 2 LAST CDS_LIB pure_quanta_power
J 0
(-1800 2875);
DISPLAY INVISIBLE (-1800 2875);
FORCEPROP 1 LAST PATH I122
J 0
(-1750 2900);
DISPLAY 0.872340 (-1750 2900);
PAINT AQUA (-1750 2900);
DISPLAY INVISIBLE (-1750 2900);
FORCEADD UNIVERSAL_GND..1
(-1800 2325);
FORCEPROP 3 LASTPIN (-1800 2375) SIG_NAME GND\g
J 0
(-1790 2385);
DISPLAY 0.659574 (-1790 2385);
PAINT MONO (-1790 2385);
DISPLAY INVISIBLE (-1790 2385);
FORCEPROP 2 LAST CDS_LIB pure_quanta_power
J 0
(-1800 2325);
DISPLAY INVISIBLE (-1800 2325);
FORCEPROP 1 LAST PATH I123
J 0
(-1725 2325);
DISPLAY 0.872340 (-1725 2325);
PAINT AQUA (-1725 2325);
DISPLAY INVISIBLE (-1725 2325);
FORCEPROP 1 LAST HDL_POWER GND
J 1
(-1775 2250);
DISPLAY 0.872340 (-1775 2250);
PAINT GREEN (-1775 2250);
DISPLAY INVISIBLE (-1775 2250);
FORCEADD Q_CAP..1
(-5075 5375);
FORCEPROP 1 LAST LOCATION PC511_1
J 0
(-5025 5475);
DISPLAY 0.489362 (-5025 5475);
PAINT SKYBLUE (-5025 5475);
FORCEPROP 0 LAST $SEC 1
J 0
(-5025 5525);
DISPLAY 0.680851 (-5025 5525);
PAINT MONO (-5025 5525);
DISPLAY INVISIBLE (-5025 5525);
FORCEPROP 0 LAST CDS_SEC 1
J 0
(-5025 5525);
DISPLAY 1.021277 (-5025 5525);
DISPLAY INVISIBLE (-5025 5525);
FORCEPROP 1 LASTPIN (-5075 5475) $PN 1
J 0
(-5065 5455);
DISPLAY 0.489362 (-5065 5455);
PAINT MONO (-5065 5455);
FORCEPROP 1 LASTPIN (-5075 5275) $PN 2
J 0
(-5065 5255);
DISPLAY 0.489362 (-5065 5255);
PAINT MONO (-5065 5255);
FORCEPROP 1 LAST MATERIAL X7R
J 0
(-5025 5275);
DISPLAY 0.489362 (-5025 5275);
PAINT SKYBLUE (-5025 5275);
FORCEPROP 1 LAST TOLERANCE 10%
J 0
(-5025 5325);
DISPLAY 0.489362 (-5025 5325);
PAINT SKYBLUE (-5025 5325);
FORCEPROP 1 LAST VALUE 0.1UF
J 0
(-5025 5425);
DISPLAY 0.489362 (-5025 5425);
PAINT SKYBLUE (-5025 5425);
FORCEPROP 1 LAST PART_NUMBER CH4104K1B00
J 0
(-5025 5225);
DISPLAY 0.489362 (-5025 5225);
PAINT SKYBLUE (-5025 5225);
FORCEPROP 1 LAST VOLTAGE 25V
J 0
(-5025 5375);
DISPLAY 0.489362 (-5025 5375);
PAINT SKYBLUE (-5025 5375);
FORCEPROP 1 LAST PACK_TYPE 0402
J 0
(-5025 5175);
DISPLAY 0.489362 (-5025 5175);
PAINT SKYBLUE (-5025 5175);
FORCEPROP 2 LAST CDS_LIB pure_quanta
J 0
(-5075 5375);
DISPLAY INVISIBLE (-5075 5375);
FORCEPROP 1 LAST PATH I124
J 0
(-5025 5525);
DISPLAY 0.978723 (-5025 5525);
PAINT WHITE (-5025 5525);
DISPLAY INVISIBLE (-5025 5525);
FORCEADD Q_CAP..1
(-5025 2450);
FORCEPROP 1 LAST LOCATION PC512_2
J 0
(-4975 2550);
DISPLAY 0.489362 (-4975 2550);
PAINT SKYBLUE (-4975 2550);
FORCEPROP 0 LAST $SEC 1
J 0
(-4975 2600);
DISPLAY 0.680851 (-4975 2600);
PAINT MONO (-4975 2600);
DISPLAY INVISIBLE (-4975 2600);
FORCEPROP 0 LAST CDS_SEC 1
J 0
(-4975 2600);
DISPLAY 1.021277 (-4975 2600);
DISPLAY INVISIBLE (-4975 2600);
FORCEPROP 1 LASTPIN (-5025 2550) $PN 1
J 0
(-5015 2530);
DISPLAY 0.489362 (-5015 2530);
PAINT MONO (-5015 2530);
FORCEPROP 1 LASTPIN (-5025 2350) $PN 2
J 0
(-5015 2330);
DISPLAY 0.489362 (-5015 2330);
PAINT MONO (-5015 2330);
FORCEPROP 1 LAST MATERIAL X7R
J 0
(-4975 2350);
DISPLAY 0.489362 (-4975 2350);
PAINT SKYBLUE (-4975 2350);
FORCEPROP 1 LAST TOLERANCE 10%
J 0
(-4975 2400);
DISPLAY 0.489362 (-4975 2400);
PAINT SKYBLUE (-4975 2400);
FORCEPROP 1 LAST VALUE 0.1UF
J 0
(-4975 2500);
DISPLAY 0.489362 (-4975 2500);
PAINT SKYBLUE (-4975 2500);
FORCEPROP 1 LAST PART_NUMBER CH4104K1B00
J 0
(-4975 2300);
DISPLAY 0.489362 (-4975 2300);
PAINT SKYBLUE (-4975 2300);
FORCEPROP 1 LAST VOLTAGE 25V
J 0
(-4975 2450);
DISPLAY 0.489362 (-4975 2450);
PAINT SKYBLUE (-4975 2450);
FORCEPROP 1 LAST PACK_TYPE 0402
J 0
(-4975 2250);
DISPLAY 0.489362 (-4975 2250);
PAINT SKYBLUE (-4975 2250);
FORCEPROP 2 LAST CDS_LIB pure_quanta
J 0
(-5025 2450);
DISPLAY INVISIBLE (-5025 2450);
FORCEPROP 1 LAST PATH I125
J 0
(-4975 2600);
DISPLAY 0.978723 (-4975 2600);
PAINT WHITE (-4975 2600);
DISPLAY INVISIBLE (-4975 2600);
FORCEADD Q_CAP..1
(-7800 4800);
FORCEPROP 1 LAST LOCATION PC505
J 0
(-7750 4900);
DISPLAY 0.489362 (-7750 4900);
PAINT SKYBLUE (-7750 4900);
FORCEPROP 0 LAST $SEC 1
J 0
(-7750 4950);
DISPLAY 0.680851 (-7750 4950);
PAINT MONO (-7750 4950);
DISPLAY INVISIBLE (-7750 4950);
FORCEPROP 0 LAST CDS_SEC 1
J 0
(-7750 4950);
DISPLAY 1.021277 (-7750 4950);
DISPLAY INVISIBLE (-7750 4950);
FORCEPROP 1 LASTPIN (-7800 4900) $PN 1
J 0
(-7790 4880);
DISPLAY 0.489362 (-7790 4880);
PAINT MONO (-7790 4880);
FORCEPROP 1 LASTPIN (-7800 4700) $PN 2
J 0
(-7790 4680);
DISPLAY 0.489362 (-7790 4680);
PAINT MONO (-7790 4680);
FORCEPROP 1 LAST MATERIAL X6S
J 0
(-7750 4700);
DISPLAY 0.489362 (-7750 4700);
PAINT SKYBLUE (-7750 4700);
FORCEPROP 1 LAST TOLERANCE 10%
J 0
(-7750 4750);
DISPLAY 0.489362 (-7750 4750);
PAINT SKYBLUE (-7750 4750);
FORCEPROP 1 LAST VALUE 2.2UF
J 0
(-7750 4850);
DISPLAY 0.489362 (-7750 4850);
PAINT SKYBLUE (-7750 4850);
FORCEPROP 1 LAST PART_NUMBER CH5222KEB01
J 0
(-7750 4650);
DISPLAY 0.489362 (-7750 4650);
PAINT SKYBLUE (-7750 4650);
FORCEPROP 1 LAST VOLTAGE 10V
J 0
(-7750 4800);
DISPLAY 0.489362 (-7750 4800);
PAINT SKYBLUE (-7750 4800);
FORCEPROP 1 LAST PACK_TYPE C0402
J 0
(-7750 4600);
DISPLAY 0.489362 (-7750 4600);
PAINT SKYBLUE (-7750 4600);
FORCEPROP 2 LAST CDS_LIB pure_quanta
J 0
(-7800 4800);
DISPLAY INVISIBLE (-7800 4800);
FORCEPROP 1 LAST PATH I126
J 0
(-7750 4950);
DISPLAY 0.978723 (-7750 4950);
PAINT WHITE (-7750 4950);
DISPLAY INVISIBLE (-7750 4950);
FORCEADD UNIVERSAL_GND..1
(-7800 4600);
FORCEPROP 3 LASTPIN (-7800 4650) SIG_NAME GND\g
J 0
(-7790 4660);
DISPLAY 0.659574 (-7790 4660);
PAINT MONO (-7790 4660);
DISPLAY INVISIBLE (-7790 4660);
FORCEPROP 2 LAST CDS_LIB pure_quanta_power
J 0
(-7800 4600);
DISPLAY INVISIBLE (-7800 4600);
FORCEPROP 1 LAST PATH I127
J 0
(-7725 4600);
DISPLAY 0.872340 (-7725 4600);
PAINT AQUA (-7725 4600);
DISPLAY INVISIBLE (-7725 4600);
FORCEPROP 1 LAST HDL_POWER GND
J 1
(-7775 4525);
DISPLAY 0.872340 (-7775 4525);
PAINT GREEN (-7775 4525);
DISPLAY INVISIBLE (-7775 4525);
FORCEADD UNIVERSAL_GND..1
(-7450 5100);
FORCEPROP 3 LASTPIN (-7450 5150) SIG_NAME GND\g
J 0
(-7440 5160);
DISPLAY 0.659574 (-7440 5160);
PAINT MONO (-7440 5160);
DISPLAY INVISIBLE (-7440 5160);
FORCEPROP 2 LAST CDS_LIB pure_quanta_power
J 0
(-7450 5100);
DISPLAY INVISIBLE (-7450 5100);
FORCEPROP 1 LAST PATH I128
J 0
(-7375 5100);
DISPLAY 0.872340 (-7375 5100);
PAINT AQUA (-7375 5100);
DISPLAY INVISIBLE (-7375 5100);
FORCEPROP 1 LAST HDL_POWER GND
J 1
(-7425 5025);
DISPLAY 0.872340 (-7425 5025);
PAINT GREEN (-7425 5025);
DISPLAY INVISIBLE (-7425 5025);
FORCEADD Q_RES..2
(-7800 5350);
FORCEPROP 1 LAST LOCATION PR326
J 0
(-7755 5475);
DISPLAY 0.489362 (-7755 5475);
PAINT SKYBLUE (-7755 5475);
FORCEPROP 0 LAST $SEC 1
J 0
(-7750 5525);
DISPLAY 0.680851 (-7750 5525);
PAINT MONO (-7750 5525);
DISPLAY INVISIBLE (-7750 5525);
FORCEPROP 0 LAST CDS_SEC 1
J 0
(-7750 5525);
DISPLAY 1.021277 (-7750 5525);
DISPLAY INVISIBLE (-7750 5525);
FORCEPROP 1 LASTPIN (-7800 5450) $PN 1
J 0
(-7795 5412);
DISPLAY 0.489362 (-7795 5412);
PAINT MONO (-7795 5412);
FORCEPROP 1 LASTPIN (-7800 5250) $PN 2
J 0
(-7795 5260);
DISPLAY 0.489362 (-7795 5260);
PAINT MONO (-7795 5260);
FORCEPROP 1 LAST WATTAGE 1/16W
J 0
(-7750 5325);
DISPLAY 0.489362 (-7750 5325);
PAINT SKYBLUE (-7750 5325);
FORCEPROP 1 LAST MATERIAL CHIP
J 0
(-7750 5275);
DISPLAY 0.489362 (-7750 5275);
PAINT SKYBLUE (-7750 5275);
FORCEPROP 1 LAST TOLERANCE 1%
J 0
(-7750 5375);
DISPLAY 0.489362 (-7750 5375);
PAINT SKYBLUE (-7750 5375);
FORCEPROP 1 LAST VALUE 2.2
J 0
(-7750 5425);
DISPLAY 0.489362 (-7750 5425);
PAINT SKYBLUE (-7750 5425);
FORCEPROP 1 LAST PART_NUMBER CS-2202FB00
J 0
(-7750 5225);
DISPLAY 0.489362 (-7750 5225);
PAINT SKYBLUE (-7750 5225);
FORCEPROP 1 LAST PACK_TYPE 0402LF
J 0
(-7750 5175);
DISPLAY 0.489362 (-7750 5175);
PAINT SKYBLUE (-7750 5175);
FORCEPROP 2 LAST CDS_LIB pure_quanta
J 0
(-7800 5350);
DISPLAY INVISIBLE (-7800 5350);
FORCEPROP 1 LAST PATH I129
J 0
(-7750 5525);
DISPLAY 0.978723 (-7750 5525);
PAINT WHITE (-7750 5525);
DISPLAY INVISIBLE (-7750 5525);
FORCEADD Q_CAP..1
(-7450 5375);
FORCEPROP 1 LAST LOCATION PC507_11P1_1
J 0
(-7400 5475);
DISPLAY 0.489362 (-7400 5475);
PAINT SKYBLUE (-7400 5475);
FORCEPROP 0 LAST $SEC 1
J 0
(-7400 5525);
DISPLAY 0.680851 (-7400 5525);
PAINT MONO (-7400 5525);
DISPLAY INVISIBLE (-7400 5525);
FORCEPROP 0 LAST CDS_SEC 1
J 0
(-7400 5525);
DISPLAY 1.021277 (-7400 5525);
DISPLAY INVISIBLE (-7400 5525);
FORCEPROP 1 LASTPIN (-7450 5475) $PN 1
J 0
(-7440 5455);
DISPLAY 0.489362 (-7440 5455);
PAINT MONO (-7440 5455);
FORCEPROP 1 LASTPIN (-7450 5275) $PN 2
J 0
(-7440 5255);
DISPLAY 0.489362 (-7440 5255);
PAINT MONO (-7440 5255);
FORCEPROP 1 LAST MATERIAL X6S
J 0
(-7400 5275);
DISPLAY 0.489362 (-7400 5275);
PAINT SKYBLUE (-7400 5275);
FORCEPROP 1 LAST TOLERANCE 10%
J 0
(-7400 5325);
DISPLAY 0.489362 (-7400 5325);
PAINT SKYBLUE (-7400 5325);
FORCEPROP 1 LAST VALUE 2.2UF
J 0
(-7400 5425);
DISPLAY 0.489362 (-7400 5425);
PAINT SKYBLUE (-7400 5425);
FORCEPROP 1 LAST PART_NUMBER CH5222KEB01
J 0
(-7400 5225);
DISPLAY 0.489362 (-7400 5225);
PAINT SKYBLUE (-7400 5225);
FORCEPROP 1 LAST VOLTAGE 10V
J 0
(-7400 5375);
DISPLAY 0.489362 (-7400 5375);
PAINT SKYBLUE (-7400 5375);
FORCEPROP 1 LAST PACK_TYPE C0402
J 0
(-7400 5175);
DISPLAY 0.489362 (-7400 5175);
PAINT SKYBLUE (-7400 5175);
FORCEPROP 2 LAST CDS_LIB pure_quanta
J 0
(-7450 5375);
DISPLAY INVISIBLE (-7450 5375);
FORCEPROP 1 LAST PATH I130
J 0
(-7400 5525);
DISPLAY 0.978723 (-7400 5525);
PAINT WHITE (-7400 5525);
DISPLAY INVISIBLE (-7400 5525);
FORCEADD VCC_CORE..1
(-7625 5950);
FORCEPROP 3 LASTPIN (-7625 5900) SIG_NAME PVDD11_S3_P1_PVCC\g
J 0
(-7615 5910);
DISPLAY 0.659574 (-7615 5910);
PAINT MONO (-7615 5910);
DISPLAY INVISIBLE (-7615 5910);
FORCEPROP 1 LAST HDL_POWER PVDD11_S3_P1_PVCC
J 1
(-7625 6000);
DISPLAY 0.489362 (-7625 6000);
PAINT GREEN (-7625 6000);
FORCEPROP 2 LAST CDS_LIB pure_quanta_power
J 0
(-7625 5950);
DISPLAY INVISIBLE (-7625 5950);
FORCEPROP 1 LAST PATH I131
J 0
(-7575 5975);
DISPLAY 0.872340 (-7575 5975);
PAINT AQUA (-7575 5975);
DISPLAY INVISIBLE (-7575 5975);
FORCEADD Q_CAP..1
(-7800 1875);
FORCEPROP 1 LAST LOCATION PC506
J 0
(-7750 1975);
DISPLAY 0.489362 (-7750 1975);
PAINT SKYBLUE (-7750 1975);
FORCEPROP 0 LAST $SEC 1
J 0
(-7750 2025);
DISPLAY 0.680851 (-7750 2025);
PAINT MONO (-7750 2025);
DISPLAY INVISIBLE (-7750 2025);
FORCEPROP 0 LAST CDS_SEC 1
J 0
(-7750 2025);
DISPLAY 1.021277 (-7750 2025);
DISPLAY INVISIBLE (-7750 2025);
FORCEPROP 1 LASTPIN (-7800 1975) $PN 1
J 0
(-7790 1955);
DISPLAY 0.489362 (-7790 1955);
PAINT MONO (-7790 1955);
FORCEPROP 1 LASTPIN (-7800 1775) $PN 2
J 0
(-7790 1755);
DISPLAY 0.489362 (-7790 1755);
PAINT MONO (-7790 1755);
FORCEPROP 1 LAST MATERIAL X6S
J 0
(-7750 1775);
DISPLAY 0.489362 (-7750 1775);
PAINT SKYBLUE (-7750 1775);
FORCEPROP 1 LAST TOLERANCE 10%
J 0
(-7750 1825);
DISPLAY 0.489362 (-7750 1825);
PAINT SKYBLUE (-7750 1825);
FORCEPROP 1 LAST VALUE 2.2UF
J 0
(-7750 1925);
DISPLAY 0.489362 (-7750 1925);
PAINT SKYBLUE (-7750 1925);
FORCEPROP 1 LAST PART_NUMBER CH5222KEB01
J 0
(-7750 1725);
DISPLAY 0.489362 (-7750 1725);
PAINT SKYBLUE (-7750 1725);
FORCEPROP 1 LAST VOLTAGE 10V
J 0
(-7750 1875);
DISPLAY 0.489362 (-7750 1875);
PAINT SKYBLUE (-7750 1875);
FORCEPROP 1 LAST PACK_TYPE C0402
J 0
(-7750 1675);
DISPLAY 0.489362 (-7750 1675);
PAINT SKYBLUE (-7750 1675);
FORCEPROP 2 LAST CDS_LIB pure_quanta
J 0
(-7800 1875);
DISPLAY INVISIBLE (-7800 1875);
FORCEPROP 1 LAST PATH I132
J 0
(-7750 2025);
DISPLAY 0.978723 (-7750 2025);
PAINT WHITE (-7750 2025);
DISPLAY INVISIBLE (-7750 2025);
FORCEADD UNIVERSAL_GND..1
(-7800 1675);
FORCEPROP 3 LASTPIN (-7800 1725) SIG_NAME GND\g
J 0
(-7790 1735);
DISPLAY 0.659574 (-7790 1735);
PAINT MONO (-7790 1735);
DISPLAY INVISIBLE (-7790 1735);
FORCEPROP 2 LAST CDS_LIB pure_quanta_power
J 0
(-7800 1675);
DISPLAY INVISIBLE (-7800 1675);
FORCEPROP 1 LAST PATH I133
J 0
(-7725 1675);
DISPLAY 0.872340 (-7725 1675);
PAINT AQUA (-7725 1675);
DISPLAY INVISIBLE (-7725 1675);
FORCEPROP 1 LAST HDL_POWER GND
J 1
(-7775 1600);
DISPLAY 0.872340 (-7775 1600);
PAINT GREEN (-7775 1600);
DISPLAY INVISIBLE (-7775 1600);
FORCEADD UNIVERSAL_GND..1
(-7450 2175);
FORCEPROP 3 LASTPIN (-7450 2225) SIG_NAME GND\g
J 0
(-7440 2235);
DISPLAY 0.659574 (-7440 2235);
PAINT MONO (-7440 2235);
DISPLAY INVISIBLE (-7440 2235);
FORCEPROP 2 LAST CDS_LIB pure_quanta_power
J 0
(-7450 2175);
DISPLAY INVISIBLE (-7450 2175);
FORCEPROP 1 LAST PATH I134
J 0
(-7375 2175);
DISPLAY 0.872340 (-7375 2175);
PAINT AQUA (-7375 2175);
DISPLAY INVISIBLE (-7375 2175);
FORCEPROP 1 LAST HDL_POWER GND
J 1
(-7425 2100);
DISPLAY 0.872340 (-7425 2100);
PAINT GREEN (-7425 2100);
DISPLAY INVISIBLE (-7425 2100);
FORCEADD Q_RES..2
(-7800 2425);
FORCEPROP 1 LAST LOCATION PR327
J 0
(-7755 2550);
DISPLAY 0.489362 (-7755 2550);
PAINT SKYBLUE (-7755 2550);
FORCEPROP 0 LAST $SEC 1
J 0
(-7750 2600);
DISPLAY 0.680851 (-7750 2600);
PAINT MONO (-7750 2600);
DISPLAY INVISIBLE (-7750 2600);
FORCEPROP 0 LAST CDS_SEC 1
J 0
(-7750 2600);
DISPLAY 1.021277 (-7750 2600);
DISPLAY INVISIBLE (-7750 2600);
FORCEPROP 1 LASTPIN (-7800 2525) $PN 1
J 0
(-7795 2487);
DISPLAY 0.489362 (-7795 2487);
PAINT MONO (-7795 2487);
FORCEPROP 1 LASTPIN (-7800 2325) $PN 2
J 0
(-7795 2335);
DISPLAY 0.489362 (-7795 2335);
PAINT MONO (-7795 2335);
FORCEPROP 1 LAST WATTAGE 1/16W
J 0
(-7750 2400);
DISPLAY 0.489362 (-7750 2400);
PAINT SKYBLUE (-7750 2400);
FORCEPROP 1 LAST MATERIAL CHIP
J 0
(-7750 2350);
DISPLAY 0.489362 (-7750 2350);
PAINT SKYBLUE (-7750 2350);
FORCEPROP 1 LAST TOLERANCE 1%
J 0
(-7750 2450);
DISPLAY 0.489362 (-7750 2450);
PAINT SKYBLUE (-7750 2450);
FORCEPROP 1 LAST VALUE 2.2
J 0
(-7750 2500);
DISPLAY 0.489362 (-7750 2500);
PAINT SKYBLUE (-7750 2500);
FORCEPROP 1 LAST PART_NUMBER CS-2202FB00
J 0
(-7750 2300);
DISPLAY 0.489362 (-7750 2300);
PAINT SKYBLUE (-7750 2300);
FORCEPROP 1 LAST PACK_TYPE 0402LF
J 0
(-7750 2250);
DISPLAY 0.489362 (-7750 2250);
PAINT SKYBLUE (-7750 2250);
FORCEPROP 2 LAST CDS_LIB pure_quanta
J 0
(-7800 2425);
DISPLAY INVISIBLE (-7800 2425);
FORCEPROP 1 LAST PATH I135
J 0
(-7750 2600);
DISPLAY 0.978723 (-7750 2600);
PAINT WHITE (-7750 2600);
DISPLAY INVISIBLE (-7750 2600);
FORCEADD Q_CAP..1
(-7450 2450);
FORCEPROP 1 LAST LOCATION PC508_11P1_2
J 0
(-7400 2550);
DISPLAY 0.489362 (-7400 2550);
PAINT SKYBLUE (-7400 2550);
FORCEPROP 0 LAST $SEC 1
J 0
(-7400 2600);
DISPLAY 0.680851 (-7400 2600);
PAINT MONO (-7400 2600);
DISPLAY INVISIBLE (-7400 2600);
FORCEPROP 0 LAST CDS_SEC 1
J 0
(-7400 2600);
DISPLAY 1.021277 (-7400 2600);
DISPLAY INVISIBLE (-7400 2600);
FORCEPROP 1 LASTPIN (-7450 2550) $PN 1
J 0
(-7440 2530);
DISPLAY 0.489362 (-7440 2530);
PAINT MONO (-7440 2530);
FORCEPROP 1 LASTPIN (-7450 2350) $PN 2
J 0
(-7440 2330);
DISPLAY 0.489362 (-7440 2330);
PAINT MONO (-7440 2330);
FORCEPROP 1 LAST MATERIAL X6S
J 0
(-7400 2350);
DISPLAY 0.489362 (-7400 2350);
PAINT SKYBLUE (-7400 2350);
FORCEPROP 1 LAST TOLERANCE 10%
J 0
(-7400 2400);
DISPLAY 0.489362 (-7400 2400);
PAINT SKYBLUE (-7400 2400);
FORCEPROP 1 LAST VALUE 2.2UF
J 0
(-7400 2500);
DISPLAY 0.489362 (-7400 2500);
PAINT SKYBLUE (-7400 2500);
FORCEPROP 1 LAST PART_NUMBER CH5222KEB01
J 0
(-7400 2300);
DISPLAY 0.489362 (-7400 2300);
PAINT SKYBLUE (-7400 2300);
FORCEPROP 1 LAST VOLTAGE 10V
J 0
(-7400 2450);
DISPLAY 0.489362 (-7400 2450);
PAINT SKYBLUE (-7400 2450);
FORCEPROP 1 LAST PACK_TYPE C0402
J 0
(-7400 2250);
DISPLAY 0.489362 (-7400 2250);
PAINT SKYBLUE (-7400 2250);
FORCEPROP 2 LAST CDS_LIB pure_quanta
J 0
(-7450 2450);
DISPLAY INVISIBLE (-7450 2450);
FORCEPROP 1 LAST PATH I136
J 0
(-7400 2600);
DISPLAY 0.978723 (-7400 2600);
PAINT WHITE (-7400 2600);
DISPLAY INVISIBLE (-7400 2600);
FORCEADD Q_CAP..1
(-3775 5375);
FORCEPROP 1 LAST LOCATION PC521_1
J 0
(-3725 5475);
DISPLAY 0.489362 (-3725 5475);
PAINT SKYBLUE (-3725 5475);
FORCEPROP 0 LAST $SEC 1
J 0
(-3725 5500);
DISPLAY 0.680851 (-3725 5500);
PAINT MONO (-3725 5500);
DISPLAY INVISIBLE (-3725 5500);
FORCEPROP 0 LAST CDS_SEC 1
J 0
(-3725 5500);
DISPLAY 1.021277 (-3725 5500);
DISPLAY INVISIBLE (-3725 5500);
FORCEPROP 1 LASTPIN (-3775 5475) $PN 1
J 0
(-3765 5455);
DISPLAY 0.489362 (-3765 5455);
PAINT MONO (-3765 5455);
FORCEPROP 1 LASTPIN (-3775 5275) $PN 2
J 0
(-3765 5255);
DISPLAY 0.489362 (-3765 5255);
PAINT MONO (-3765 5255);
FORCEPROP 1 LAST MATERIAL X6S
J 0
(-3725 5275);
DISPLAY 0.489362 (-3725 5275);
PAINT SKYBLUE (-3725 5275);
FORCEPROP 1 LAST TOLERANCE 10%
J 0
(-3725 5325);
DISPLAY 0.489362 (-3725 5325);
PAINT SKYBLUE (-3725 5325);
FORCEPROP 1 LAST VALUE 10UF
J 0
(-3725 5425);
DISPLAY 0.489362 (-3725 5425);
PAINT SKYBLUE (-3725 5425);
FORCEPROP 1 LAST PART_NUMBER CH6104KEA00
J 0
(-3725 5225);
DISPLAY 0.489362 (-3725 5225);
PAINT SKYBLUE (-3725 5225);
FORCEPROP 1 LAST VOLTAGE 25V
J 0
(-3725 5375);
DISPLAY 0.489362 (-3725 5375);
PAINT SKYBLUE (-3725 5375);
FORCEPROP 1 LAST PACK_TYPE C0805
J 0
(-3725 5175);
DISPLAY 0.489362 (-3725 5175);
PAINT SKYBLUE (-3725 5175);
FORCEPROP 2 LAST CDS_LIB pure_quanta
J 0
(-3775 5375);
DISPLAY INVISIBLE (-3775 5375);
FORCEPROP 1 LAST PATH I138
J 0
(-3725 5525);
DISPLAY 0.978723 (-3725 5525);
PAINT WHITE (-3725 5525);
DISPLAY INVISIBLE (-3725 5525);
FORCEADD Q_CAP..1
(-3750 2450);
FORCEPROP 1 LAST LOCATION PC27
J 0
(-3700 2550);
DISPLAY 0.489362 (-3700 2550);
PAINT SKYBLUE (-3700 2550);
FORCEPROP 0 LAST $SEC 1
J 0
(-3700 2575);
DISPLAY 0.680851 (-3700 2575);
PAINT MONO (-3700 2575);
DISPLAY INVISIBLE (-3700 2575);
FORCEPROP 0 LAST CDS_SEC 1
J 0
(-3700 2575);
DISPLAY 1.021277 (-3700 2575);
DISPLAY INVISIBLE (-3700 2575);
FORCEPROP 1 LASTPIN (-3750 2550) $PN 1
J 0
(-3740 2530);
DISPLAY 0.489362 (-3740 2530);
PAINT MONO (-3740 2530);
FORCEPROP 1 LASTPIN (-3750 2350) $PN 2
J 0
(-3740 2330);
DISPLAY 0.489362 (-3740 2330);
PAINT MONO (-3740 2330);
FORCEPROP 1 LAST MATERIAL X6S
J 0
(-3700 2350);
DISPLAY 0.489362 (-3700 2350);
PAINT SKYBLUE (-3700 2350);
FORCEPROP 1 LAST TOLERANCE 10%
J 0
(-3700 2400);
DISPLAY 0.489362 (-3700 2400);
PAINT SKYBLUE (-3700 2400);
FORCEPROP 1 LAST VALUE 10UF
J 0
(-3700 2500);
DISPLAY 0.489362 (-3700 2500);
PAINT SKYBLUE (-3700 2500);
FORCEPROP 1 LAST PART_NUMBER CH6104KEA00
J 0
(-3700 2300);
DISPLAY 0.489362 (-3700 2300);
PAINT SKYBLUE (-3700 2300);
FORCEPROP 1 LAST VOLTAGE 25V
J 0
(-3700 2450);
DISPLAY 0.489362 (-3700 2450);
PAINT SKYBLUE (-3700 2450);
FORCEPROP 1 LAST PACK_TYPE C0805
J 0
(-3700 2250);
DISPLAY 0.489362 (-3700 2250);
PAINT SKYBLUE (-3700 2250);
FORCEPROP 2 LAST CDS_LIB pure_quanta
J 0
(-3750 2450);
DISPLAY INVISIBLE (-3750 2450);
FORCEPROP 1 LAST PATH I139
J 0
(-3700 2600);
DISPLAY 0.978723 (-3700 2600);
PAINT WHITE (-3700 2600);
DISPLAY INVISIBLE (-3700 2600);
FORCEADD UNIVERSAL_GND..1
(-4625 3525);
FORCEPROP 3 LASTPIN (-4625 3575) SIG_NAME GND\g
J 0
(-4615 3585);
DISPLAY 0.659574 (-4615 3585);
PAINT MONO (-4615 3585);
DISPLAY INVISIBLE (-4615 3585);
FORCEPROP 2 LAST CDS_LIB pure_quanta_power
J 0
(-4625 3525);
DISPLAY INVISIBLE (-4625 3525);
FORCEPROP 1 LAST PATH I140
J 0
(-4550 3525);
DISPLAY 0.872340 (-4550 3525);
PAINT AQUA (-4550 3525);
DISPLAY INVISIBLE (-4550 3525);
FORCEPROP 1 LAST HDL_POWER GND
J 1
(-4600 3450);
DISPLAY 0.872340 (-4600 3450);
PAINT GREEN (-4600 3450);
DISPLAY INVISIBLE (-4600 3450);
FORCEADD Q_RES..2
(-4625 3750);
FORCEPROP 1 LAST LOCATION PR520
J 0
(-4580 3875);
DISPLAY 0.489362 (-4580 3875);
PAINT SKYBLUE (-4580 3875);
FORCEPROP 0 LAST $SEC 1
J 0
(-4575 3925);
DISPLAY 0.680851 (-4575 3925);
PAINT MONO (-4575 3925);
DISPLAY INVISIBLE (-4575 3925);
FORCEPROP 0 LAST CDS_SEC 1
J 0
(-4575 3925);
DISPLAY 1.021277 (-4575 3925);
DISPLAY INVISIBLE (-4575 3925);
FORCEPROP 1 LASTPIN (-4625 3850) $PN 1
J 0
(-4620 3812);
DISPLAY 0.489362 (-4620 3812);
PAINT MONO (-4620 3812);
FORCEPROP 1 LASTPIN (-4625 3650) $PN 2
J 0
(-4620 3660);
DISPLAY 0.489362 (-4620 3660);
PAINT MONO (-4620 3660);
FORCEPROP 1 LAST WATTAGE 1/8W
J 0
(-4585 3725);
DISPLAY 0.489362 (-4585 3725);
PAINT SKYBLUE (-4585 3725);
FORCEPROP 1 LAST MATERIAL EMPTY
J 0
(-4585 3675);
DISPLAY 0.489362 (-4585 3675);
PAINT RED (-4585 3675);
FORCEPROP 1 LAST TOLERANCE 1%
J 0
(-4580 3775);
DISPLAY 0.489362 (-4580 3775);
PAINT SKYBLUE (-4580 3775);
FORCEPROP 1 LAST VALUE 1.5
J 0
(-4580 3825);
DISPLAY 0.489362 (-4580 3825);
PAINT SKYBLUE (-4580 3825);
FORCEPROP 1 LAST PART_NUMBER CS-1504FB00
J 0
(-4585 3625);
DISPLAY 0.489362 (-4585 3625);
PAINT SKYBLUE (-4585 3625);
FORCEPROP 1 LAST PACK_TYPE 0402LF
J 0
(-4585 3575);
DISPLAY 0.489362 (-4585 3575);
PAINT SKYBLUE (-4585 3575);
FORCEPROP 2 LAST CDS_LIB pure_quanta
J 0
(-4625 3750);
DISPLAY INVISIBLE (-4625 3750);
FORCEPROP 1 LAST PATH I141
J 0
(-4575 3925);
DISPLAY 0.978723 (-4575 3925);
PAINT WHITE (-4575 3925);
DISPLAY INVISIBLE (-4575 3925);
FORCEADD Q_CAP..1
(-4625 4275);
FORCEPROP 1 LAST LOCATION PC315
J 0
(-4575 4375);
DISPLAY 0.489362 (-4575 4375);
PAINT SKYBLUE (-4575 4375);
FORCEPROP 0 LAST $SEC 1
J 0
(-4575 4425);
DISPLAY 0.680851 (-4575 4425);
PAINT MONO (-4575 4425);
DISPLAY INVISIBLE (-4575 4425);
FORCEPROP 0 LAST CDS_SEC 1
J 0
(-4575 4425);
DISPLAY 1.021277 (-4575 4425);
DISPLAY INVISIBLE (-4575 4425);
FORCEPROP 1 LASTPIN (-4625 4375) $PN 1
J 0
(-4615 4355);
DISPLAY 0.489362 (-4615 4355);
PAINT MONO (-4615 4355);
FORCEPROP 1 LASTPIN (-4625 4175) $PN 2
J 0
(-4615 4155);
DISPLAY 0.489362 (-4615 4155);
PAINT MONO (-4615 4155);
FORCEPROP 1 LAST MATERIAL EMPTY
J 0
(-4575 4175);
DISPLAY 0.489362 (-4575 4175);
PAINT RED (-4575 4175);
FORCEPROP 1 LAST TOLERANCE 10%
J 0
(-4575 4225);
DISPLAY 0.489362 (-4575 4225);
PAINT SKYBLUE (-4575 4225);
FORCEPROP 1 LAST VALUE 560PF
J 0
(-4575 4325);
DISPLAY 0.489362 (-4575 4325);
PAINT SKYBLUE (-4575 4325);
FORCEPROP 1 LAST PART_NUMBER CH1566K1B09
J 0
(-4575 4125);
DISPLAY 0.489362 (-4575 4125);
PAINT SKYBLUE (-4575 4125);
FORCEPROP 1 LAST VOLTAGE 50V
J 0
(-4575 4275);
DISPLAY 0.489362 (-4575 4275);
PAINT SKYBLUE (-4575 4275);
FORCEPROP 1 LAST PACK_TYPE C0402
J 0
(-4575 4075);
DISPLAY 0.489362 (-4575 4075);
PAINT SKYBLUE (-4575 4075);
FORCEPROP 2 LAST CDS_LIB pure_quanta
J 0
(-4625 4275);
DISPLAY INVISIBLE (-4625 4275);
FORCEPROP 1 LAST PATH I142
J 0
(-4575 4425);
DISPLAY 0.978723 (-4575 4425);
PAINT WHITE (-4575 4425);
DISPLAY INVISIBLE (-4575 4425);
FORCEADD UNIVERSAL_GND..1
(-4575 650);
FORCEPROP 3 LASTPIN (-4575 700) SIG_NAME GND\g
J 0
(-4565 710);
DISPLAY 0.659574 (-4565 710);
PAINT MONO (-4565 710);
DISPLAY INVISIBLE (-4565 710);
FORCEPROP 2 LAST CDS_LIB pure_quanta_power
J 0
(-4575 650);
DISPLAY INVISIBLE (-4575 650);
FORCEPROP 1 LAST PATH I143
J 0
(-4500 650);
DISPLAY 0.872340 (-4500 650);
PAINT AQUA (-4500 650);
DISPLAY INVISIBLE (-4500 650);
FORCEPROP 1 LAST HDL_POWER GND
J 1
(-4550 575);
DISPLAY 0.872340 (-4550 575);
PAINT GREEN (-4550 575);
DISPLAY INVISIBLE (-4550 575);
FORCEADD Q_RES..2
(-4575 875);
FORCEPROP 1 LAST LOCATION PR519
J 0
(-4530 1000);
DISPLAY 0.489362 (-4530 1000);
PAINT SKYBLUE (-4530 1000);
FORCEPROP 0 LAST $SEC 1
J 0
(-4525 1050);
DISPLAY 0.680851 (-4525 1050);
PAINT MONO (-4525 1050);
DISPLAY INVISIBLE (-4525 1050);
FORCEPROP 0 LAST CDS_SEC 1
J 0
(-4525 1050);
DISPLAY 1.021277 (-4525 1050);
DISPLAY INVISIBLE (-4525 1050);
FORCEPROP 1 LASTPIN (-4575 975) $PN 1
J 0
(-4570 937);
DISPLAY 0.489362 (-4570 937);
PAINT MONO (-4570 937);
FORCEPROP 1 LASTPIN (-4575 775) $PN 2
J 0
(-4570 785);
DISPLAY 0.489362 (-4570 785);
PAINT MONO (-4570 785);
FORCEPROP 1 LAST WATTAGE 1/8W
J 0
(-4535 850);
DISPLAY 0.489362 (-4535 850);
PAINT SKYBLUE (-4535 850);
FORCEPROP 1 LAST MATERIAL EMPTY
J 0
(-4535 800);
DISPLAY 0.489362 (-4535 800);
PAINT RED (-4535 800);
FORCEPROP 1 LAST TOLERANCE 1%
J 0
(-4530 900);
DISPLAY 0.489362 (-4530 900);
PAINT SKYBLUE (-4530 900);
FORCEPROP 1 LAST VALUE 1.5
J 0
(-4530 950);
DISPLAY 0.489362 (-4530 950);
PAINT SKYBLUE (-4530 950);
FORCEPROP 1 LAST PART_NUMBER CS-1504FB00
J 0
(-4535 750);
DISPLAY 0.489362 (-4535 750);
PAINT SKYBLUE (-4535 750);
FORCEPROP 1 LAST PACK_TYPE 0402LF
J 0
(-4535 700);
DISPLAY 0.489362 (-4535 700);
PAINT SKYBLUE (-4535 700);
FORCEPROP 2 LAST CDS_LIB pure_quanta
J 0
(-4575 875);
DISPLAY INVISIBLE (-4575 875);
FORCEPROP 1 LAST PATH I144
J 0
(-4525 1050);
DISPLAY 0.978723 (-4525 1050);
PAINT WHITE (-4525 1050);
DISPLAY INVISIBLE (-4525 1050);
FORCEADD Q_CAP..1
(-4575 1375);
FORCEPROP 1 LAST LOCATION PC255
J 0
(-4525 1475);
DISPLAY 0.489362 (-4525 1475);
PAINT SKYBLUE (-4525 1475);
FORCEPROP 0 LAST $SEC 1
J 0
(-4525 1525);
DISPLAY 0.680851 (-4525 1525);
PAINT MONO (-4525 1525);
DISPLAY INVISIBLE (-4525 1525);
FORCEPROP 0 LAST CDS_SEC 1
J 0
(-4525 1525);
DISPLAY 1.021277 (-4525 1525);
DISPLAY INVISIBLE (-4525 1525);
FORCEPROP 1 LASTPIN (-4575 1475) $PN 1
J 0
(-4565 1455);
DISPLAY 0.489362 (-4565 1455);
PAINT MONO (-4565 1455);
FORCEPROP 1 LASTPIN (-4575 1275) $PN 2
J 0
(-4565 1255);
DISPLAY 0.489362 (-4565 1255);
PAINT MONO (-4565 1255);
FORCEPROP 1 LAST MATERIAL EMPTY
J 0
(-4525 1275);
DISPLAY 0.489362 (-4525 1275);
PAINT RED (-4525 1275);
FORCEPROP 1 LAST TOLERANCE 10%
J 0
(-4525 1325);
DISPLAY 0.489362 (-4525 1325);
PAINT SKYBLUE (-4525 1325);
FORCEPROP 1 LAST VALUE 560PF
J 0
(-4525 1425);
DISPLAY 0.489362 (-4525 1425);
PAINT SKYBLUE (-4525 1425);
FORCEPROP 1 LAST PART_NUMBER CH1566K1B09
J 0
(-4525 1225);
DISPLAY 0.489362 (-4525 1225);
PAINT SKYBLUE (-4525 1225);
FORCEPROP 1 LAST VOLTAGE 50V
J 0
(-4525 1375);
DISPLAY 0.489362 (-4525 1375);
PAINT SKYBLUE (-4525 1375);
FORCEPROP 1 LAST PACK_TYPE C0402
J 0
(-4525 1175);
DISPLAY 0.489362 (-4525 1175);
PAINT SKYBLUE (-4525 1175);
FORCEPROP 2 LAST CDS_LIB pure_quanta
J 0
(-4575 1375);
DISPLAY INVISIBLE (-4575 1375);
FORCEPROP 1 LAST PATH I145
J 0
(-4525 1525);
DISPLAY 0.978723 (-4525 1525);
PAINT WHITE (-4525 1525);
DISPLAY INVISIBLE (-4525 1525);
FORCEADD Q_RES..1
R 1
(-8450 5750);
FORCEPROP 1 LAST LOCATION PR387
J 0
(-8425 5900);
DISPLAY 0.489362 (-8425 5900);
PAINT SKYBLUE (-8425 5900);
FORCEPROP 0 LAST $SEC 1
R 1
J 0
(-8425 5925);
DISPLAY 0.680851 (-8425 5925);
PAINT MONO (-8425 5925);
DISPLAY INVISIBLE (-8425 5925);
FORCEPROP 0 LAST CDS_SEC 1
R 1
J 0
(-8425 5925);
DISPLAY 1.021277 (-8425 5925);
DISPLAY INVISIBLE (-8425 5925);
FORCEPROP 1 LASTPIN (-8450 5650) $PN 1
R 1
J 0
(-8462 5662);
DISPLAY 0.787234 (-8462 5662);
PAINT MONO (-8462 5662);
DISPLAY INVISIBLE (-8462 5662);
FORCEPROP 1 LASTPIN (-8450 5850) $PN 2
R 1
J 0
(-8462 5812);
DISPLAY 0.787234 (-8462 5812);
PAINT MONO (-8462 5812);
DISPLAY INVISIBLE (-8462 5812);
FORCEPROP 1 LAST WATTAGE 1/16W
J 0
(-8425 5750);
DISPLAY 0.489362 (-8425 5750);
PAINT SKYBLUE (-8425 5750);
FORCEPROP 1 LAST MATERIAL CHIP
J 0
(-8425 5700);
DISPLAY 0.489362 (-8425 5700);
PAINT SKYBLUE (-8425 5700);
FORCEPROP 1 LAST TOLERANCE 5%
J 0
(-8425 5800);
DISPLAY 0.489362 (-8425 5800);
PAINT SKYBLUE (-8425 5800);
FORCEPROP 1 LAST VALUE 0
J 2
(-8400 5850);
DISPLAY 0.489362 (-8400 5850);
PAINT SKYBLUE (-8400 5850);
FORCEPROP 1 LAST PART_NUMBER CS00002JB38
J 0
(-8425 5650);
DISPLAY 0.489362 (-8425 5650);
PAINT SKYBLUE (-8425 5650);
FORCEPROP 1 LAST PACK_TYPE 0402LF
J 0
(-8425 5600);
DISPLAY 0.489362 (-8425 5600);
PAINT SKYBLUE (-8425 5600);
FORCEPROP 2 LAST CDS_LIB pure_quanta
J 0
(-8450 5750);
DISPLAY INVISIBLE (-8450 5750);
FORCEPROP 1 LAST PATH I146
R 1
J 0
(-8600 5700);
DISPLAY 0.978723 (-8600 5700);
PAINT WHITE (-8600 5700);
DISPLAY INVISIBLE (-8600 5700);
FORCEADD VCC_CORE..1
(-8450 5950);
FORCEPROP 3 LASTPIN (-8450 5900) SIG_NAME P5V_STBY\g
J 0
(-8440 5910);
DISPLAY 0.659574 (-8440 5910);
PAINT MONO (-8440 5910);
DISPLAY INVISIBLE (-8440 5910);
FORCEPROP 1 LAST HDL_POWER P5V_STBY
J 1
(-8450 6000);
DISPLAY 0.489362 (-8450 6000);
PAINT GREEN (-8450 6000);
FORCEPROP 2 LAST CDS_LIB pure_quanta_power
J 0
(-8450 5950);
DISPLAY INVISIBLE (-8450 5950);
FORCEPROP 1 LAST PATH I147
J 0
(-8400 5975);
DISPLAY 0.872340 (-8400 5975);
PAINT AQUA (-8400 5975);
DISPLAY INVISIBLE (-8400 5975);
FORCEADD Q_RES..1
R 1
(-8100 5750);
FORCEPROP 1 LAST LOCATION PR394
J 0
(-8050 5900);
DISPLAY 0.489362 (-8050 5900);
PAINT SKYBLUE (-8050 5900);
FORCEPROP 0 LAST $SEC 1
R 1
J 0
(-8050 5925);
DISPLAY 0.680851 (-8050 5925);
PAINT MONO (-8050 5925);
DISPLAY INVISIBLE (-8050 5925);
FORCEPROP 0 LAST CDS_SEC 1
R 1
J 0
(-8050 5925);
DISPLAY 1.021277 (-8050 5925);
DISPLAY INVISIBLE (-8050 5925);
FORCEPROP 1 LASTPIN (-8100 5650) $PN 1
R 1
J 0
(-8112 5662);
DISPLAY 0.787234 (-8112 5662);
PAINT MONO (-8112 5662);
DISPLAY INVISIBLE (-8112 5662);
FORCEPROP 1 LASTPIN (-8100 5850) $PN 2
R 1
J 0
(-8112 5812);
DISPLAY 0.787234 (-8112 5812);
PAINT MONO (-8112 5812);
DISPLAY INVISIBLE (-8112 5812);
FORCEPROP 1 LAST WATTAGE 1/16W
J 0
(-8050 5750);
DISPLAY 0.489362 (-8050 5750);
PAINT SKYBLUE (-8050 5750);
FORCEPROP 1 LAST MATERIAL EMPTY
J 0
(-8050 5700);
DISPLAY 0.489362 (-8050 5700);
PAINT RED (-8050 5700);
FORCEPROP 1 LAST TOLERANCE 5%
J 0
(-8050 5800);
DISPLAY 0.489362 (-8050 5800);
PAINT SKYBLUE (-8050 5800);
FORCEPROP 1 LAST VALUE 0
J 2
(-8025 5850);
DISPLAY 0.489362 (-8025 5850);
PAINT SKYBLUE (-8025 5850);
FORCEPROP 1 LAST PART_NUMBER CS00002JB38
J 0
(-8050 5650);
DISPLAY 0.489362 (-8050 5650);
PAINT SKYBLUE (-8050 5650);
FORCEPROP 1 LAST PACK_TYPE 0402LF
J 0
(-8050 5600);
DISPLAY 0.489362 (-8050 5600);
PAINT SKYBLUE (-8050 5600);
FORCEPROP 2 LAST CDS_LIB pure_quanta
J 0
(-8100 5750);
DISPLAY INVISIBLE (-8100 5750);
FORCEPROP 1 LAST PATH I148
R 1
J 0
(-8250 5700);
DISPLAY 0.978723 (-8250 5700);
PAINT WHITE (-8250 5700);
DISPLAY INVISIBLE (-8250 5700);
FORCEADD VCC_CORE..1
(-8100 5950);
FORCEPROP 3 LASTPIN (-8100 5900) SIG_NAME P3V3_STBY\g
J 0
(-8090 5910);
DISPLAY 0.659574 (-8090 5910);
PAINT MONO (-8090 5910);
DISPLAY INVISIBLE (-8090 5910);
FORCEPROP 1 LAST HDL_POWER P3V3_STBY
J 1
(-8100 6000);
DISPLAY 0.489362 (-8100 6000);
PAINT GREEN (-8100 6000);
FORCEPROP 2 LAST CDS_LIB pure_quanta_power
J 0
(-8100 5950);
DISPLAY INVISIBLE (-8100 5950);
FORCEPROP 1 LAST PATH I149
J 0
(-8050 5975);
DISPLAY 0.872340 (-8050 5975);
PAINT AQUA (-8050 5975);
DISPLAY INVISIBLE (-8050 5975);
FORCEADD Q_RES..1
(-7225 4175);
FORCEPROP 1 LAST LOCATION PR328
J 0
(-7225 4225);
DISPLAY 0.489362 (-7225 4225);
PAINT SKYBLUE (-7225 4225);
FORCEPROP 0 LAST $SEC 1
J 0
(-7225 4250);
DISPLAY 0.680851 (-7225 4250);
PAINT MONO (-7225 4250);
DISPLAY INVISIBLE (-7225 4250);
FORCEPROP 0 LAST CDS_SEC 1
J 0
(-7225 4250);
DISPLAY 1.021277 (-7225 4250);
DISPLAY INVISIBLE (-7225 4250);
FORCEPROP 1 LASTPIN (-7325 4175) $PN 1
J 0
(-7313 4187);
DISPLAY 0.489362 (-7313 4187);
PAINT MONO (-7313 4187);
FORCEPROP 1 LASTPIN (-7125 4175) $PN 2
J 0
(-7163 4187);
DISPLAY 0.489362 (-7163 4187);
PAINT MONO (-7163 4187);
FORCEPROP 1 LAST WATTAGE 1/16W
J 0
(-7125 4075);
DISPLAY 0.489362 (-7125 4075);
PAINT SKYBLUE (-7125 4075);
FORCEPROP 1 LAST MATERIAL EMPTY
J 0
(-7525 4075);
DISPLAY 0.489362 (-7525 4075);
PAINT RED (-7525 4075);
FORCEPROP 1 LAST TOLERANCE 1%
J 0
(-7100 4200);
DISPLAY 0.489362 (-7100 4200);
PAINT SKYBLUE (-7100 4200);
FORCEPROP 1 LAST VALUE 4.87K
J 2
(-7300 4200);
DISPLAY 0.489362 (-7300 4200);
PAINT SKYBLUE (-7300 4200);
FORCEPROP 1 LAST PART_NUMBER CS24872FB07
J 0
(-7525 4125);
DISPLAY 0.489362 (-7525 4125);
PAINT SKYBLUE (-7525 4125);
FORCEPROP 1 LAST PACK_TYPE 0402LF
J 0
(-7125 4125);
DISPLAY 0.489362 (-7125 4125);
PAINT SKYBLUE (-7125 4125);
FORCEPROP 2 LAST CDS_LIB pure_quanta
J 0
(-7225 4175);
DISPLAY INVISIBLE (-7225 4175);
FORCEPROP 1 LAST PATH I15
J 0
(-7275 4325);
DISPLAY 0.978723 (-7275 4325);
PAINT WHITE (-7275 4325);
DISPLAY INVISIBLE (-7275 4325);
FORCEADD VCC_CORE..1
(-7800 2825);
FORCEPROP 3 LASTPIN (-7800 2775) SIG_NAME PVDD11_S3_P1_PVCC\g
J 0
(-7790 2785);
DISPLAY 0.659574 (-7790 2785);
PAINT MONO (-7790 2785);
DISPLAY INVISIBLE (-7790 2785);
FORCEPROP 1 LAST HDL_POWER PVDD11_S3_P1_PVCC
J 1
(-7800 2875);
DISPLAY 0.489362 (-7800 2875);
PAINT GREEN (-7800 2875);
FORCEPROP 2 LAST CDS_LIB pure_quanta_power
J 0
(-7800 2825);
DISPLAY INVISIBLE (-7800 2825);
FORCEPROP 1 LAST PATH I150
J 0
(-7750 2850);
DISPLAY 0.872340 (-7750 2850);
PAINT AQUA (-7750 2850);
DISPLAY INVISIBLE (-7750 2850);
FORCEADD Q_RES..2
(-1150 4275);
FORCEPROP 1 LAST LOCATION PR395
J 0
(-1105 4400);
DISPLAY 0.489362 (-1105 4400);
PAINT SKYBLUE (-1105 4400);
FORCEPROP 0 LAST $SEC 1
J 0
(-1100 4425);
DISPLAY 0.680851 (-1100 4425);
PAINT MONO (-1100 4425);
DISPLAY INVISIBLE (-1100 4425);
FORCEPROP 0 LAST CDS_SEC 1
J 0
(-1100 4425);
DISPLAY 1.021277 (-1100 4425);
DISPLAY INVISIBLE (-1100 4425);
FORCEPROP 1 LASTPIN (-1150 4375) $PN 1
J 0
(-1145 4337);
DISPLAY 0.787234 (-1145 4337);
PAINT MONO (-1145 4337);
DISPLAY INVISIBLE (-1145 4337);
FORCEPROP 1 LASTPIN (-1150 4175) $PN 2
J 0
(-1145 4185);
DISPLAY 0.787234 (-1145 4185);
PAINT MONO (-1145 4185);
DISPLAY INVISIBLE (-1145 4185);
FORCEPROP 1 LAST WATTAGE 1/16W
J 0
(-1110 4250);
DISPLAY 0.489362 (-1110 4250);
PAINT SKYBLUE (-1110 4250);
FORCEPROP 1 LAST MATERIAL CHIP
J 0
(-1110 4200);
DISPLAY 0.489362 (-1110 4200);
PAINT SKYBLUE (-1110 4200);
FORCEPROP 1 LAST TOLERANCE 1%
J 0
(-1105 4300);
DISPLAY 0.489362 (-1105 4300);
PAINT SKYBLUE (-1105 4300);
FORCEPROP 1 LAST VALUE 1K
J 0
(-1105 4350);
DISPLAY 0.489362 (-1105 4350);
PAINT SKYBLUE (-1105 4350);
FORCEPROP 1 LAST PART_NUMBER TMP_QCS21002FB24
J 0
(-1110 4150);
DISPLAY 0.489362 (-1110 4150);
PAINT SKYBLUE (-1110 4150);
FORCEPROP 1 LAST PACK_TYPE 0402LF
J 0
(-1110 4100);
DISPLAY 0.489362 (-1110 4100);
PAINT SKYBLUE (-1110 4100);
FORCEPROP 2 LAST CDS_LIB pure_quanta
J 0
(-1150 4275);
DISPLAY INVISIBLE (-1150 4275);
FORCEPROP 1 LAST PATH I151
J 0
(-1100 4450);
DISPLAY 0.978723 (-1100 4450);
PAINT WHITE (-1100 4450);
DISPLAY INVISIBLE (-1100 4450);
FORCEADD Q_CAPP..1
(-2200 2625);
FORCEPROP 1 LAST LOCATION PC802
J 0
(-2150 2725);
DISPLAY 0.489362 (-2150 2725);
PAINT SKYBLUE (-2150 2725);
FORCEPROP 0 LAST $SEC 1
J 0
(-2150 2750);
DISPLAY 0.680851 (-2150 2750);
PAINT MONO (-2150 2750);
DISPLAY INVISIBLE (-2150 2750);
FORCEPROP 0 LAST CDS_SEC 1
J 0
(-2150 2750);
DISPLAY 0.680851 (-2150 2750);
DISPLAY INVISIBLE (-2150 2750);
FORCEPROP 1 LASTPIN (-2200 2725) $PN 1
J 0
(-2190 2710);
DISPLAY 0.489362 (-2190 2710);
PAINT MONO (-2190 2710);
FORCEPROP 1 LASTPIN (-2200 2525) $PN 2
J 0
(-2190 2510);
DISPLAY 0.489362 (-2190 2510);
PAINT MONO (-2190 2510);
FORCEPROP 1 LAST MATERIAL SPCAP
J 0
(-2150 2525);
DISPLAY 0.489362 (-2150 2525);
PAINT SKYBLUE (-2150 2525);
FORCEPROP 1 LAST TOLERANCE 20%
J 0
(-2150 2625);
DISPLAY 0.489362 (-2150 2625);
PAINT SKYBLUE (-2150 2625);
FORCEPROP 1 LAST VALUE 470UF
J 0
(-2150 2675);
DISPLAY 0.489362 (-2150 2675);
PAINT SKYBLUE (-2150 2675);
FORCEPROP 1 LAST PART_NUMBER CH747LM8825
J 0
(-2150 2425);
DISPLAY 0.489362 (-2150 2425);
PAINT SKYBLUE (-2150 2425);
FORCEPROP 1 LAST VOLTAGE 2.5V
J 0
(-2150 2575);
DISPLAY 0.489362 (-2150 2575);
PAINT SKYBLUE (-2150 2575);
FORCEPROP 1 LAST PACK_TYPE SMLF
J 0
(-2150 2475);
DISPLAY 0.489362 (-2150 2475);
PAINT SKYBLUE (-2150 2475);
FORCEPROP 2 LAST CDS_LIB pure_quanta
J 0
(-2200 2625);
DISPLAY INVISIBLE (-2200 2625);
FORCEPROP 1 LAST PATH I152
J 0
(-2150 2775);
DISPLAY 0.978723 (-2150 2775);
DISPLAY INVISIBLE (-2150 2775);
FORCEADD Q_CAPP..1
(-825 2650);
FORCEPROP 1 LAST LOCATION PC803
J 0
(-775 2750);
DISPLAY 0.489362 (-775 2750);
PAINT SKYBLUE (-775 2750);
FORCEPROP 0 LAST $SEC 1
J 0
(-775 2775);
DISPLAY 0.680851 (-775 2775);
PAINT MONO (-775 2775);
DISPLAY INVISIBLE (-775 2775);
FORCEPROP 0 LAST CDS_SEC 1
J 0
(-775 2775);
DISPLAY 0.680851 (-775 2775);
DISPLAY INVISIBLE (-775 2775);
FORCEPROP 1 LASTPIN (-825 2750) $PN 1
J 0
(-815 2735);
DISPLAY 0.489362 (-815 2735);
PAINT MONO (-815 2735);
FORCEPROP 1 LASTPIN (-825 2550) $PN 2
J 0
(-815 2535);
DISPLAY 0.489362 (-815 2535);
PAINT MONO (-815 2535);
FORCEPROP 1 LAST MATERIAL OSCON
J 0
(-775 2550);
DISPLAY 0.489362 (-775 2550);
PAINT SKYBLUE (-775 2550);
FORCEPROP 1 LAST TOLERANCE 20%
J 0
(-775 2650);
DISPLAY 0.489362 (-775 2650);
PAINT SKYBLUE (-775 2650);
FORCEPROP 1 LAST VALUE 390UF
J 0
(-775 2700);
DISPLAY 0.489362 (-775 2700);
PAINT SKYBLUE (-775 2700);
FORCEPROP 1 LAST PART_NUMBER CC7390JMZ12
J 0
(-775 2450);
DISPLAY 0.489362 (-775 2450);
PAINT SKYBLUE (-775 2450);
FORCEPROP 1 LAST VOLTAGE 2.5V
J 0
(-775 2600);
DISPLAY 0.489362 (-775 2600);
PAINT SKYBLUE (-775 2600);
FORCEPROP 1 LAST PACK_TYPE SMLF
J 0
(-775 2500);
DISPLAY 0.489362 (-775 2500);
PAINT SKYBLUE (-775 2500);
FORCEPROP 2 LAST CDS_LIB pure_quanta
J 0
(-825 2650);
DISPLAY INVISIBLE (-825 2650);
FORCEPROP 1 LAST PATH I153
J 0
(-775 2800);
DISPLAY 0.978723 (-775 2800);
DISPLAY INVISIBLE (-775 2800);
FORCEADD Q_RES..1
(-4800 4825);
FORCEPROP 1 LAST LOCATION PR330
J 0
(-4850 4900);
DISPLAY 0.489362 (-4850 4900);
PAINT SKYBLUE (-4850 4900);
FORCEPROP 0 LAST $SEC 1
J 0
(-4775 4900);
DISPLAY 0.680851 (-4775 4900);
PAINT MONO (-4775 4900);
DISPLAY INVISIBLE (-4775 4900);
FORCEPROP 0 LAST CDS_SEC 1
J 0
(-4775 4900);
DISPLAY 1.021277 (-4775 4900);
DISPLAY INVISIBLE (-4775 4900);
FORCEPROP 1 LASTPIN (-4900 4825) $PN 1
J 0
(-4888 4837);
DISPLAY 0.489362 (-4888 4837);
PAINT MONO (-4888 4837);
FORCEPROP 1 LASTPIN (-4700 4825) $PN 2
J 0
(-4738 4837);
DISPLAY 0.489362 (-4738 4837);
PAINT MONO (-4738 4837);
FORCEPROP 1 LAST PACK_TYPE 0402LF
J 0
(-4700 4725);
DISPLAY 0.489362 (-4700 4725);
PAINT SKYBLUE (-4700 4725);
FORCEPROP 1 LAST TOLERANCE 1%
J 0
(-4700 4850);
DISPLAY 0.489362 (-4700 4850);
PAINT SKYBLUE (-4700 4850);
FORCEPROP 1 LAST MATERIAL CHIP
J 0
(-5050 4725);
DISPLAY 0.489362 (-5050 4725);
PAINT SKYBLUE (-5050 4725);
FORCEPROP 1 LAST WATTAGE 1/16W
J 0
(-4700 4775);
DISPLAY 0.489362 (-4700 4775);
PAINT SKYBLUE (-4700 4775);
FORCEPROP 1 LAST VALUE 4.7
J 2
(-4900 4850);
DISPLAY 0.489362 (-4900 4850);
PAINT SKYBLUE (-4900 4850);
FORCEPROP 1 LAST PART_NUMBER CS-4702FB19
J 0
(-5050 4775);
DISPLAY 0.489362 (-5050 4775);
PAINT SKYBLUE (-5050 4775);
FORCEPROP 1 LAST PATH I19
J 0
(-4850 4975);
DISPLAY 0.978723 (-4850 4975);
PAINT WHITE (-4850 4975);
DISPLAY INVISIBLE (-4850 4975);
FORCEPROP 2 LAST CDS_LIB pure_quanta
J 0
(-4800 4825);
DISPLAY INVISIBLE (-4800 4825);
FORCEADD UNIVERSAL_GND..1
(-5450 3750);
FORCEPROP 3 LASTPIN (-5450 3800) SIG_NAME GND\g
J 0
(-5440 3810);
DISPLAY 0.659574 (-5440 3810);
PAINT MONO (-5440 3810);
DISPLAY INVISIBLE (-5440 3810);
FORCEPROP 2 LAST CDS_LIB pure_quanta_power
J 0
(-5450 3750);
DISPLAY INVISIBLE (-5450 3750);
FORCEPROP 1 LAST PATH I2
J 0
(-5375 3750);
DISPLAY 0.872340 (-5375 3750);
PAINT AQUA (-5375 3750);
DISPLAY INVISIBLE (-5375 3750);
FORCEPROP 1 LAST HDL_POWER GND
J 1
(-5425 3675);
DISPLAY 0.872340 (-5425 3675);
PAINT GREEN (-5425 3675);
DISPLAY INVISIBLE (-5425 3675);
FORCEADD Q_CAP..1
(-5400 5375);
FORCEPROP 1 LAST LOCATION PC509_1
J 0
(-5350 5475);
DISPLAY 0.489362 (-5350 5475);
PAINT SKYBLUE (-5350 5475);
FORCEPROP 0 LAST $SEC 1
J 0
(-5350 5500);
DISPLAY 0.680851 (-5350 5500);
PAINT MONO (-5350 5500);
DISPLAY INVISIBLE (-5350 5500);
FORCEPROP 0 LAST CDS_SEC 1
J 0
(-5350 5500);
DISPLAY 1.021277 (-5350 5500);
DISPLAY INVISIBLE (-5350 5500);
FORCEPROP 1 LASTPIN (-5400 5475) $PN 1
J 0
(-5390 5455);
DISPLAY 0.489362 (-5390 5455);
PAINT MONO (-5390 5455);
FORCEPROP 1 LASTPIN (-5400 5275) $PN 2
J 0
(-5390 5255);
DISPLAY 0.489362 (-5390 5255);
PAINT MONO (-5390 5255);
FORCEPROP 1 LAST MATERIAL X6S
J 0
(-5350 5275);
DISPLAY 0.489362 (-5350 5275);
PAINT SKYBLUE (-5350 5275);
FORCEPROP 1 LAST TOLERANCE 10%
J 0
(-5350 5325);
DISPLAY 0.489362 (-5350 5325);
PAINT SKYBLUE (-5350 5325);
FORCEPROP 1 LAST VALUE 1UF
J 0
(-5350 5425);
DISPLAY 0.489362 (-5350 5425);
PAINT SKYBLUE (-5350 5425);
FORCEPROP 1 LAST PART_NUMBER CH5104KEB02
J 0
(-5350 5225);
DISPLAY 0.489362 (-5350 5225);
PAINT SKYBLUE (-5350 5225);
FORCEPROP 1 LAST VOLTAGE 25V
J 0
(-5350 5375);
DISPLAY 0.489362 (-5350 5375);
PAINT SKYBLUE (-5350 5375);
FORCEPROP 1 LAST PACK_TYPE C0402
J 0
(-5350 5175);
DISPLAY 0.489362 (-5350 5175);
PAINT SKYBLUE (-5350 5175);
FORCEPROP 2 LAST CDS_LIB pure_quanta
J 0
(-5400 5375);
DISPLAY INVISIBLE (-5400 5375);
FORCEPROP 1 LAST PATH I23
J 0
(-5350 5525);
DISPLAY 0.978723 (-5350 5525);
PAINT WHITE (-5350 5525);
DISPLAY INVISIBLE (-5350 5525);
FORCEADD Q_CAP..1
(-4775 5375);
FORCEPROP 1 LAST LOCATION PC513_1
J 0
(-4725 5475);
DISPLAY 0.489362 (-4725 5475);
PAINT SKYBLUE (-4725 5475);
FORCEPROP 0 LAST $SEC 1
J 0
(-4725 5500);
DISPLAY 0.680851 (-4725 5500);
PAINT MONO (-4725 5500);
DISPLAY INVISIBLE (-4725 5500);
FORCEPROP 0 LAST CDS_SEC 1
J 0
(-4725 5500);
DISPLAY 1.021277 (-4725 5500);
DISPLAY INVISIBLE (-4725 5500);
FORCEPROP 1 LASTPIN (-4775 5475) $PN 1
J 0
(-4765 5455);
DISPLAY 0.489362 (-4765 5455);
PAINT MONO (-4765 5455);
FORCEPROP 1 LASTPIN (-4775 5275) $PN 2
J 0
(-4765 5255);
DISPLAY 0.489362 (-4765 5255);
PAINT MONO (-4765 5255);
FORCEPROP 1 LAST MATERIAL X6S
J 0
(-4725 5275);
DISPLAY 0.489362 (-4725 5275);
PAINT SKYBLUE (-4725 5275);
FORCEPROP 1 LAST TOLERANCE 10%
J 0
(-4725 5325);
DISPLAY 0.489362 (-4725 5325);
PAINT SKYBLUE (-4725 5325);
FORCEPROP 1 LAST VALUE 10UF
J 0
(-4725 5425);
DISPLAY 0.489362 (-4725 5425);
PAINT SKYBLUE (-4725 5425);
FORCEPROP 1 LAST PART_NUMBER CH6104KEA00
J 0
(-4725 5225);
DISPLAY 0.489362 (-4725 5225);
PAINT SKYBLUE (-4725 5225);
FORCEPROP 1 LAST VOLTAGE 25V
J 0
(-4725 5375);
DISPLAY 0.489362 (-4725 5375);
PAINT SKYBLUE (-4725 5375);
FORCEPROP 1 LAST PACK_TYPE C0805
J 0
(-4725 5175);
DISPLAY 0.489362 (-4725 5175);
PAINT SKYBLUE (-4725 5175);
FORCEPROP 2 LAST CDS_LIB pure_quanta
J 0
(-4775 5375);
DISPLAY INVISIBLE (-4775 5375);
FORCEPROP 1 LAST PATH I24
J 0
(-4725 5525);
DISPLAY 0.978723 (-4725 5525);
PAINT WHITE (-4725 5525);
DISPLAY INVISIBLE (-4725 5525);
FORCEADD Q_CAP..1
(-4400 5375);
FORCEPROP 1 LAST LOCATION PC515_1
J 0
(-4350 5475);
DISPLAY 0.489362 (-4350 5475);
PAINT SKYBLUE (-4350 5475);
FORCEPROP 0 LAST $SEC 1
J 0
(-4350 5500);
DISPLAY 0.680851 (-4350 5500);
PAINT MONO (-4350 5500);
DISPLAY INVISIBLE (-4350 5500);
FORCEPROP 0 LAST CDS_SEC 1
J 0
(-4350 5500);
DISPLAY 1.021277 (-4350 5500);
DISPLAY INVISIBLE (-4350 5500);
FORCEPROP 1 LASTPIN (-4400 5475) $PN 1
J 0
(-4390 5455);
DISPLAY 0.489362 (-4390 5455);
PAINT MONO (-4390 5455);
FORCEPROP 1 LASTPIN (-4400 5275) $PN 2
J 0
(-4390 5255);
DISPLAY 0.489362 (-4390 5255);
PAINT MONO (-4390 5255);
FORCEPROP 1 LAST MATERIAL X6S
J 0
(-4350 5275);
DISPLAY 0.489362 (-4350 5275);
PAINT SKYBLUE (-4350 5275);
FORCEPROP 1 LAST TOLERANCE 10%
J 0
(-4350 5325);
DISPLAY 0.489362 (-4350 5325);
PAINT SKYBLUE (-4350 5325);
FORCEPROP 1 LAST VALUE 10UF
J 0
(-4350 5425);
DISPLAY 0.489362 (-4350 5425);
PAINT SKYBLUE (-4350 5425);
FORCEPROP 1 LAST PART_NUMBER CH6104KEA00
J 0
(-4350 5225);
DISPLAY 0.489362 (-4350 5225);
PAINT SKYBLUE (-4350 5225);
FORCEPROP 1 LAST VOLTAGE 25V
J 0
(-4350 5375);
DISPLAY 0.489362 (-4350 5375);
PAINT SKYBLUE (-4350 5375);
FORCEPROP 1 LAST PACK_TYPE C0805
J 0
(-4350 5175);
DISPLAY 0.489362 (-4350 5175);
PAINT SKYBLUE (-4350 5175);
FORCEPROP 2 LAST CDS_LIB pure_quanta
J 0
(-4400 5375);
DISPLAY INVISIBLE (-4400 5375);
FORCEPROP 1 LAST PATH I25
J 0
(-4350 5525);
DISPLAY 0.978723 (-4350 5525);
PAINT WHITE (-4350 5525);
DISPLAY INVISIBLE (-4350 5525);
FORCEADD Q_CAP..1
(-4100 5375);
FORCEPROP 1 LAST LOCATION PC517_1
J 0
(-4050 5475);
DISPLAY 0.489362 (-4050 5475);
PAINT SKYBLUE (-4050 5475);
FORCEPROP 0 LAST $SEC 1
J 0
(-4050 5500);
DISPLAY 0.680851 (-4050 5500);
PAINT MONO (-4050 5500);
DISPLAY INVISIBLE (-4050 5500);
FORCEPROP 0 LAST CDS_SEC 1
J 0
(-4050 5500);
DISPLAY 1.021277 (-4050 5500);
DISPLAY INVISIBLE (-4050 5500);
FORCEPROP 1 LASTPIN (-4100 5475) $PN 1
J 0
(-4090 5455);
DISPLAY 0.489362 (-4090 5455);
PAINT MONO (-4090 5455);
FORCEPROP 1 LASTPIN (-4100 5275) $PN 2
J 0
(-4090 5255);
DISPLAY 0.489362 (-4090 5255);
PAINT MONO (-4090 5255);
FORCEPROP 1 LAST MATERIAL X6S
J 0
(-4050 5275);
DISPLAY 0.489362 (-4050 5275);
PAINT SKYBLUE (-4050 5275);
FORCEPROP 1 LAST TOLERANCE 10%
J 0
(-4050 5325);
DISPLAY 0.489362 (-4050 5325);
PAINT SKYBLUE (-4050 5325);
FORCEPROP 1 LAST VALUE 10UF
J 0
(-4050 5425);
DISPLAY 0.489362 (-4050 5425);
PAINT SKYBLUE (-4050 5425);
FORCEPROP 1 LAST PART_NUMBER CH6104KEA00
J 0
(-4050 5225);
DISPLAY 0.489362 (-4050 5225);
PAINT SKYBLUE (-4050 5225);
FORCEPROP 1 LAST VOLTAGE 25V
J 0
(-4050 5375);
DISPLAY 0.489362 (-4050 5375);
PAINT SKYBLUE (-4050 5375);
FORCEPROP 1 LAST PACK_TYPE C0805
J 0
(-4050 5175);
DISPLAY 0.489362 (-4050 5175);
PAINT SKYBLUE (-4050 5175);
FORCEPROP 2 LAST CDS_LIB pure_quanta
J 0
(-4100 5375);
DISPLAY INVISIBLE (-4100 5375);
FORCEPROP 1 LAST PATH I26
J 0
(-4050 5525);
DISPLAY 0.978723 (-4050 5525);
PAINT WHITE (-4050 5525);
DISPLAY INVISIBLE (-4050 5525);
FORCEADD Q_CAPP..1
(-3375 5375);
FORCEPROP 1 LAST LOCATION PC522
J 0
(-3325 5475);
DISPLAY 0.489362 (-3325 5475);
PAINT SKYBLUE (-3325 5475);
FORCEPROP 0 LAST $SEC 1
J 0
(-3325 5500);
DISPLAY 0.680851 (-3325 5500);
PAINT MONO (-3325 5500);
DISPLAY INVISIBLE (-3325 5500);
FORCEPROP 0 LAST CDS_SEC 1
J 0
(-3325 5500);
DISPLAY 1.021277 (-3325 5500);
DISPLAY INVISIBLE (-3325 5500);
FORCEPROP 1 LASTPIN (-3375 5475) $PN 1
J 0
(-3365 5460);
DISPLAY 0.489362 (-3365 5460);
PAINT MONO (-3365 5460);
FORCEPROP 1 LASTPIN (-3375 5275) $PN 2
J 0
(-3365 5260);
DISPLAY 0.489362 (-3365 5260);
PAINT MONO (-3365 5260);
FORCEPROP 1 LAST MATERIAL OSCON
J 0
(-3325 5275);
DISPLAY 0.489362 (-3325 5275);
PAINT SKYBLUE (-3325 5275);
FORCEPROP 1 LAST TOLERANCE 20%
J 0
(-3325 5375);
DISPLAY 0.489362 (-3325 5375);
PAINT SKYBLUE (-3325 5375);
FORCEPROP 1 LAST VALUE 220UF
J 0
(-3325 5425);
DISPLAY 0.489362 (-3325 5425);
PAINT SKYBLUE (-3325 5425);
FORCEPROP 1 LAST PART_NUMBER SP_CC72204MD02
J 0
(-3325 5175);
DISPLAY 0.489362 (-3325 5175);
PAINT SKYBLUE (-3325 5175);
FORCEPROP 1 LAST VOLTAGE 25V
J 0
(-3325 5325);
DISPLAY 0.489362 (-3325 5325);
PAINT SKYBLUE (-3325 5325);
FORCEPROP 1 LAST PACK_TYPE THLF
J 0
(-3325 5225);
DISPLAY 0.489362 (-3325 5225);
PAINT SKYBLUE (-3325 5225);
FORCEPROP 2 LAST CDS_LIB pure_quanta
J 0
(-3375 5375);
DISPLAY INVISIBLE (-3375 5375);
FORCEPROP 1 LAST PATH I27
J 0
(-3325 5525);
DISPLAY 0.978723 (-3325 5525);
DISPLAY INVISIBLE (-3325 5525);
FORCEADD Q_CAP..1
(-2325 4300);
FORCEPROP 1 LAST LOCATION PC524
J 0
(-2275 4400);
DISPLAY 0.489362 (-2275 4400);
PAINT SKYBLUE (-2275 4400);
FORCEPROP 0 LAST $SEC 1
J 0
(-2275 4425);
DISPLAY 0.680851 (-2275 4425);
PAINT MONO (-2275 4425);
DISPLAY INVISIBLE (-2275 4425);
FORCEPROP 0 LAST CDS_SEC 1
J 0
(-2275 4425);
DISPLAY 1.021277 (-2275 4425);
DISPLAY INVISIBLE (-2275 4425);
FORCEPROP 1 LASTPIN (-2325 4400) $PN 1
J 0
(-2315 4380);
DISPLAY 0.489362 (-2315 4380);
PAINT MONO (-2315 4380);
FORCEPROP 1 LASTPIN (-2325 4200) $PN 2
J 0
(-2315 4180);
DISPLAY 0.489362 (-2315 4180);
PAINT MONO (-2315 4180);
FORCEPROP 1 LAST MATERIAL X7R
J 0
(-2275 4200);
DISPLAY 0.489362 (-2275 4200);
PAINT SKYBLUE (-2275 4200);
FORCEPROP 1 LAST TOLERANCE 10%
J 0
(-2275 4250);
DISPLAY 0.489362 (-2275 4250);
PAINT SKYBLUE (-2275 4250);
FORCEPROP 1 LAST VALUE 100NF
J 0
(-2275 4350);
DISPLAY 0.489362 (-2275 4350);
PAINT SKYBLUE (-2275 4350);
FORCEPROP 1 LAST PART_NUMBER CH4106K1B01
J 0
(-2275 4150);
DISPLAY 0.489362 (-2275 4150);
PAINT SKYBLUE (-2275 4150);
FORCEPROP 1 LAST VOLTAGE 50V
J 0
(-2275 4300);
DISPLAY 0.489362 (-2275 4300);
PAINT SKYBLUE (-2275 4300);
FORCEPROP 1 LAST PACK_TYPE C0402
J 0
(-2275 4100);
DISPLAY 0.489362 (-2275 4100);
PAINT SKYBLUE (-2275 4100);
FORCEPROP 2 LAST CDS_LIB pure_quanta
J 0
(-2325 4300);
DISPLAY INVISIBLE (-2325 4300);
FORCEPROP 1 LAST PATH I29
J 0
(-2275 4450);
DISPLAY 0.978723 (-2275 4450);
PAINT WHITE (-2275 4450);
DISPLAY INVISIBLE (-2275 4450);
FORCEADD OFFPAGE..1
(-8125 4375);
FORCEPROP 2 LAST $XR1 201 
J 0
(-8527 4375);
DISPLAY 0.638298 (-8527 4375);
PAINT MONO (-8527 4375);
FORCEPROP 2 LAST $XR0 200 
J 0
(-8407 4375);
DISPLAY 0.638298 (-8407 4375);
PAINT MONO (-8407 4375);
FORCEPROP 1 LAST OFFPAGE TRUE
J 0
(-7800 4250);
DISPLAY 0.872340 (-7800 4250);
PAINT GREEN (-7800 4250);
DISPLAY INVISIBLE (-7800 4250);
FORCEPROP 2 LAST CDS_LIB standard
J 0
(-8125 4375);
DISPLAY INVISIBLE (-8125 4375);
FORCEPROP 1 LAST COMMENT_BODY TRUE
J 0
(-8000 4275);
DISPLAY 0.872340 (-8000 4275);
PAINT GREEN (-8000 4275);
DISPLAY INVISIBLE (-8000 4275);
FORCEPROP 2 LAST PATH I3
J 0
(-8075 4450);
DISPLAY 1.021277 (-8075 4450);
DISPLAY INVISIBLE (-8075 4450);
FORCEADD UNIVERSAL_GND..1
(-3900 5025);
FORCEPROP 3 LASTPIN (-3900 5075) SIG_NAME GND\g
J 0
(-3890 5085);
DISPLAY 0.659574 (-3890 5085);
PAINT MONO (-3890 5085);
DISPLAY INVISIBLE (-3890 5085);
FORCEPROP 2 LAST CDS_LIB pure_quanta_power
J 0
(-3900 5025);
DISPLAY INVISIBLE (-3900 5025);
FORCEPROP 1 LAST PATH I31
J 0
(-3825 5025);
DISPLAY 0.872340 (-3825 5025);
PAINT AQUA (-3825 5025);
DISPLAY INVISIBLE (-3825 5025);
FORCEPROP 1 LAST HDL_POWER GND
J 1
(-3875 4950);
DISPLAY 0.872340 (-3875 4950);
PAINT GREEN (-3875 4950);
DISPLAY INVISIBLE (-3875 4950);
FORCEADD Q_INDUCTOR..1
(-2950 5575);
FORCEPROP 1 LAST LOCATION PL56
J 0
(-3075 5735);
DISPLAY 0.489362 (-3075 5735);
PAINT SKYBLUE (-3075 5735);
FORCEPROP 0 LAST $SEC 1
J 0
(-3075 5850);
DISPLAY 0.680851 (-3075 5850);
PAINT MONO (-3075 5850);
DISPLAY INVISIBLE (-3075 5850);
FORCEPROP 0 LAST CDS_SEC 1
J 0
(-3075 5850);
DISPLAY 1.021277 (-3075 5850);
DISPLAY INVISIBLE (-3075 5850);
FORCEPROP 0 LASTPIN (-3050 5550) $PN 1
J 2
(-3060 5560);
DISPLAY 0.489362 (-3060 5560);
PAINT MONO (-3060 5560);
FORCEPROP 0 LASTPIN (-2850 5550) $PN 2
J 0
(-2840 5560);
DISPLAY 0.489362 (-2840 5560);
PAINT MONO (-2840 5560);
FORCEPROP 1 LAST MATERIAL IND
J 0
(-3075 5630);
DISPLAY 0.489362 (-3075 5630);
PAINT SKYBLUE (-3075 5630);
FORCEPROP 2 LAST VALUE 100NH/16A
J 0
(-3075 5825);
DISPLAY 0.489362 (-3075 5825);
PAINT SKYBLUE (-3075 5825);
FORCEPROP 1 LAST PART_NUMBER CV+10G0MZ12
J 0
(-3075 5685);
DISPLAY 0.489362 (-3075 5685);
PAINT SKYBLUE (-3075 5685);
FORCEPROP 2 LAST PACK_TYPE SMLF
J 0
(-3075 5775);
DISPLAY 0.489362 (-3075 5775);
PAINT SKYBLUE (-3075 5775);
FORCEPROP 2 LAST CDS_LIB pure_quanta
J 0
(-2950 5575);
DISPLAY INVISIBLE (-2950 5575);
FORCEPROP 1 LAST NEEDS_NO_SIZE TRUE
J 0
(-2950 5575);
DISPLAY 0.468085 (-2950 5575);
PAINT GREEN (-2950 5575);
DISPLAY INVISIBLE (-2950 5575);
FORCEPROP 1 LAST PATH I34
J 0
(-2875 5630);
DISPLAY 0.723404 (-2875 5630);
PAINT GREEN (-2875 5630);
DISPLAY INVISIBLE (-2875 5630);
FORCEADD VCC_CORE..1
(-2675 5625);
FORCEPROP 3 LASTPIN (-2675 5575) SIG_NAME P12V_STBY\g
J 0
(-2665 5585);
DISPLAY 0.659574 (-2665 5585);
PAINT MONO (-2665 5585);
DISPLAY INVISIBLE (-2665 5585);
FORCEPROP 1 LAST HDL_POWER P12V_STBY
J 1
(-2675 5675);
DISPLAY 0.489362 (-2675 5675);
PAINT GREEN (-2675 5675);
FORCEPROP 2 LAST CDS_LIB pure_quanta_power
J 0
(-2675 5625);
DISPLAY INVISIBLE (-2675 5625);
FORCEPROP 1 LAST PATH I35
J 0
(-2625 5650);
DISPLAY 0.872340 (-2625 5650);
PAINT AQUA (-2625 5650);
DISPLAY INVISIBLE (-2625 5650);
FORCEADD Q_CAP..1
(-2000 4300);
FORCEPROP 1 LAST LOCATION PC526_1
J 0
(-1950 4400);
DISPLAY 0.489362 (-1950 4400);
PAINT SKYBLUE (-1950 4400);
FORCEPROP 0 LAST $SEC 1
J 0
(-1950 4425);
DISPLAY 0.680851 (-1950 4425);
PAINT MONO (-1950 4425);
DISPLAY INVISIBLE (-1950 4425);
FORCEPROP 0 LAST CDS_SEC 1
J 0
(-1950 4425);
DISPLAY 1.021277 (-1950 4425);
DISPLAY INVISIBLE (-1950 4425);
FORCEPROP 1 LASTPIN (-2000 4400) $PN 1
J 0
(-1990 4380);
DISPLAY 0.489362 (-1990 4380);
PAINT MONO (-1990 4380);
FORCEPROP 1 LASTPIN (-2000 4200) $PN 2
J 0
(-1990 4180);
DISPLAY 0.489362 (-1990 4180);
PAINT MONO (-1990 4180);
FORCEPROP 1 LAST MATERIAL X6S
J 0
(-1950 4200);
DISPLAY 0.489362 (-1950 4200);
PAINT SKYBLUE (-1950 4200);
FORCEPROP 1 LAST TOLERANCE 20%
J 0
(-1950 4250);
DISPLAY 0.489362 (-1950 4250);
PAINT SKYBLUE (-1950 4250);
FORCEPROP 1 LAST VALUE 22UF
J 0
(-1950 4350);
DISPLAY 0.489362 (-1950 4350);
PAINT SKYBLUE (-1950 4350);
FORCEPROP 1 LAST PART_NUMBER TMP_QCH622KMEA01
J 0
(-1950 4150);
DISPLAY 0.489362 (-1950 4150);
PAINT SKYBLUE (-1950 4150);
FORCEPROP 1 LAST VOLTAGE 4V
J 0
(-1950 4300);
DISPLAY 0.489362 (-1950 4300);
PAINT SKYBLUE (-1950 4300);
FORCEPROP 1 LAST PACK_TYPE 0805
J 0
(-1950 4100);
DISPLAY 0.489362 (-1950 4100);
PAINT SKYBLUE (-1950 4100);
FORCEPROP 2 LAST CDS_LIB pure_quanta
J 0
(-2000 4300);
DISPLAY INVISIBLE (-2000 4300);
FORCEPROP 1 LAST PATH I37
J 0
(-1950 4450);
DISPLAY 0.978723 (-1950 4450);
PAINT WHITE (-1950 4450);
DISPLAY INVISIBLE (-1950 4450);
FORCEADD UNIVERSAL_GND..1
(-1150 3925);
FORCEPROP 3 LASTPIN (-1150 3975) SIG_NAME GND\g
J 0
(-1140 3985);
DISPLAY 0.659574 (-1140 3985);
PAINT MONO (-1140 3985);
DISPLAY INVISIBLE (-1140 3985);
FORCEPROP 2 LAST CDS_LIB pure_quanta_power
J 0
(-1150 3925);
DISPLAY INVISIBLE (-1150 3925);
FORCEPROP 1 LAST PATH I38
J 0
(-1075 3925);
DISPLAY 0.872340 (-1075 3925);
PAINT AQUA (-1075 3925);
DISPLAY INVISIBLE (-1075 3925);
FORCEPROP 1 LAST HDL_POWER GND
J 1
(-1125 3850);
DISPLAY 0.872340 (-1125 3850);
PAINT GREEN (-1125 3850);
DISPLAY INVISIBLE (-1125 3850);
FORCEADD Q_CAP..1
(-1575 4300);
FORCEPROP 1 LAST LOCATION PC529_1
J 0
(-1525 4400);
DISPLAY 0.489362 (-1525 4400);
PAINT SKYBLUE (-1525 4400);
FORCEPROP 0 LAST $SEC 1
J 0
(-1525 4425);
DISPLAY 0.680851 (-1525 4425);
PAINT MONO (-1525 4425);
DISPLAY INVISIBLE (-1525 4425);
FORCEPROP 0 LAST CDS_SEC 1
J 0
(-1525 4425);
DISPLAY 1.021277 (-1525 4425);
DISPLAY INVISIBLE (-1525 4425);
FORCEPROP 1 LASTPIN (-1575 4400) $PN 1
J 0
(-1565 4380);
DISPLAY 0.489362 (-1565 4380);
PAINT MONO (-1565 4380);
FORCEPROP 1 LASTPIN (-1575 4200) $PN 2
J 0
(-1565 4180);
DISPLAY 0.489362 (-1565 4180);
PAINT MONO (-1565 4180);
FORCEPROP 1 LAST MATERIAL X6S
J 0
(-1525 4200);
DISPLAY 0.489362 (-1525 4200);
PAINT SKYBLUE (-1525 4200);
FORCEPROP 1 LAST TOLERANCE 20%
J 0
(-1525 4250);
DISPLAY 0.489362 (-1525 4250);
PAINT SKYBLUE (-1525 4250);
FORCEPROP 1 LAST VALUE 22UF
J 0
(-1525 4350);
DISPLAY 0.489362 (-1525 4350);
PAINT SKYBLUE (-1525 4350);
FORCEPROP 1 LAST PART_NUMBER TMP_QCH622KMEA01
J 0
(-1525 4150);
DISPLAY 0.489362 (-1525 4150);
PAINT SKYBLUE (-1525 4150);
FORCEPROP 1 LAST VOLTAGE 4V
J 0
(-1525 4300);
DISPLAY 0.489362 (-1525 4300);
PAINT SKYBLUE (-1525 4300);
FORCEPROP 1 LAST PACK_TYPE 0805
J 0
(-1525 4100);
DISPLAY 0.489362 (-1525 4100);
PAINT SKYBLUE (-1525 4100);
FORCEPROP 2 LAST CDS_LIB pure_quanta
J 0
(-1575 4300);
DISPLAY INVISIBLE (-1575 4300);
FORCEPROP 1 LAST PATH I39
J 0
(-1525 4450);
DISPLAY 0.978723 (-1525 4450);
PAINT WHITE (-1525 4450);
DISPLAY INVISIBLE (-1525 4450);
FORCEADD Q_CAP..1
(-7900 4200);
FORCEPROP 1 LAST LOCATION PC503_1
J 0
(-7850 4300);
DISPLAY 0.489362 (-7850 4300);
PAINT SKYBLUE (-7850 4300);
FORCEPROP 0 LAST $SEC 1
J 0
(-7850 4325);
DISPLAY 0.680851 (-7850 4325);
PAINT MONO (-7850 4325);
DISPLAY INVISIBLE (-7850 4325);
FORCEPROP 0 LAST CDS_SEC 1
J 0
(-7850 4325);
DISPLAY 1.021277 (-7850 4325);
DISPLAY INVISIBLE (-7850 4325);
FORCEPROP 1 LASTPIN (-7900 4300) $PN 1
J 0
(-7890 4280);
DISPLAY 0.489362 (-7890 4280);
PAINT MONO (-7890 4280);
FORCEPROP 1 LASTPIN (-7900 4100) $PN 2
J 0
(-7890 4080);
DISPLAY 0.489362 (-7890 4080);
PAINT MONO (-7890 4080);
FORCEPROP 1 LAST MATERIAL X7R
J 0
(-7850 4100);
DISPLAY 0.489362 (-7850 4100);
PAINT SKYBLUE (-7850 4100);
FORCEPROP 1 LAST TOLERANCE 10%
J 0
(-7850 4150);
DISPLAY 0.489362 (-7850 4150);
PAINT SKYBLUE (-7850 4150);
FORCEPROP 1 LAST VALUE 0.1UF
J 0
(-7850 4250);
DISPLAY 0.489362 (-7850 4250);
PAINT SKYBLUE (-7850 4250);
FORCEPROP 1 LAST PART_NUMBER CH4104K1B00
J 0
(-7850 4050);
DISPLAY 0.489362 (-7850 4050);
PAINT SKYBLUE (-7850 4050);
FORCEPROP 1 LAST VOLTAGE 25V
J 0
(-7850 4200);
DISPLAY 0.489362 (-7850 4200);
PAINT SKYBLUE (-7850 4200);
FORCEPROP 1 LAST PACK_TYPE 0402
J 0
(-7850 4000);
DISPLAY 0.489362 (-7850 4000);
PAINT SKYBLUE (-7850 4000);
FORCEPROP 2 LAST CDS_LIB pure_quanta
J 0
(-7900 4200);
DISPLAY INVISIBLE (-7900 4200);
FORCEPROP 1 LAST PATH I4
J 0
(-7850 4350);
DISPLAY 0.978723 (-7850 4350);
PAINT WHITE (-7850 4350);
DISPLAY INVISIBLE (-7850 4350);
FORCEADD VCC_CORE..1
(-1150 4600);
FORCEPROP 3 LASTPIN (-1150 4550) SIG_NAME PVDD11_S3_P1\g
J 0
(-1140 4560);
DISPLAY 0.659574 (-1140 4560);
PAINT MONO (-1140 4560);
DISPLAY INVISIBLE (-1140 4560);
FORCEPROP 1 LAST HDL_POWER PVDD11_S3_P1
J 1
(-1150 4650);
DISPLAY 0.489362 (-1150 4650);
PAINT GREEN (-1150 4650);
FORCEPROP 2 LAST CDS_LIB pure_quanta_power
J 0
(-1150 4600);
DISPLAY INVISIBLE (-1150 4600);
FORCEPROP 1 LAST PATH I40
J 0
(-1100 4625);
DISPLAY 0.872340 (-1100 4625);
PAINT AQUA (-1100 4625);
DISPLAY INVISIBLE (-1100 4625);
FORCEADD Q_CAP..1
(-3900 4700);
FORCEPROP 1 LAST LOCATION PC519
J 0
(-3850 4825);
DISPLAY 0.489362 (-3850 4825);
PAINT SKYBLUE (-3850 4825);
FORCEPROP 0 LAST $SEC 1
J 0
(-3850 4850);
DISPLAY 0.680851 (-3850 4850);
PAINT MONO (-3850 4850);
DISPLAY INVISIBLE (-3850 4850);
FORCEPROP 0 LAST CDS_SEC 1
J 0
(-3850 4850);
DISPLAY 1.021277 (-3850 4850);
DISPLAY INVISIBLE (-3850 4850);
FORCEPROP 1 LASTPIN (-3900 4800) $PN 1
J 0
(-3890 4780);
DISPLAY 0.489362 (-3890 4780);
PAINT MONO (-3890 4780);
FORCEPROP 1 LASTPIN (-3900 4600) $PN 2
J 0
(-3890 4580);
DISPLAY 0.489362 (-3890 4580);
PAINT MONO (-3890 4580);
FORCEPROP 1 LAST MATERIAL X7R
J 0
(-3850 4625);
DISPLAY 0.489362 (-3850 4625);
PAINT SKYBLUE (-3850 4625);
FORCEPROP 1 LAST TOLERANCE 10%
J 0
(-3850 4675);
DISPLAY 0.489362 (-3850 4675);
PAINT SKYBLUE (-3850 4675);
FORCEPROP 1 LAST VALUE 0.22UF
J 0
(-3850 4775);
DISPLAY 0.489362 (-3850 4775);
PAINT SKYBLUE (-3850 4775);
FORCEPROP 1 LAST PART_NUMBER CH4223K1B00
J 0
(-3850 4575);
DISPLAY 0.489362 (-3850 4575);
PAINT SKYBLUE (-3850 4575);
FORCEPROP 1 LAST VOLTAGE 16V
J 0
(-3850 4725);
DISPLAY 0.489362 (-3850 4725);
PAINT SKYBLUE (-3850 4725);
FORCEPROP 1 LAST PACK_TYPE 0402
J 0
(-3850 4525);
DISPLAY 0.489362 (-3850 4525);
PAINT SKYBLUE (-3850 4525);
FORCEPROP 2 LAST CDS_LIB pure_quanta
J 0
(-3900 4700);
DISPLAY INVISIBLE (-3900 4700);
FORCEPROP 1 LAST PATH I43
J 0
(-3850 4850);
DISPLAY 0.978723 (-3850 4850);
PAINT WHITE (-3850 4850);
DISPLAY INVISIBLE (-3850 4850);
FORCEADD ISL99390FRZTR5935..1
(-6075 4475);
FORCEPROP 1 LAST LOCATION PU44
J 0
(-6375 5350);
DISPLAY 0.489362 (-6375 5350);
PAINT SKYBLUE (-6375 5350);
FORCEPROP 2 LAST $SEC 1
J 0
(-6375 5500);
DISPLAY 0.680851 (-6375 5500);
PAINT MONO (-6375 5500);
DISPLAY INVISIBLE (-6375 5500);
FORCEPROP 2 LAST CDS_SEC 1
J 0
(-6375 5500);
DISPLAY 1.021277 (-6375 5500);
DISPLAY INVISIBLE (-6375 5500);
FORCEPROP 2 LASTPIN (-5675 4025) $PN 2
J 0
(-5665 4035);
DISPLAY 0.489362 (-5665 4035);
PAINT MONO (-5665 4035);
FORCEPROP 2 LASTPIN (-5675 4825) $PN 33
J 0
(-5665 4835);
DISPLAY 0.489362 (-5665 4835);
PAINT MONO (-5665 4835);
FORCEPROP 2 LASTPIN (-6525 4225) $PN 31
J 2
(-6535 4235);
DISPLAY 0.489362 (-6535 4235);
PAINT MONO (-6535 4235);
FORCEPROP 2 LASTPIN (-6525 4625) $PN 35
J 2
(-6535 4635);
DISPLAY 0.489362 (-6535 4635);
PAINT MONO (-6535 4635);
FORCEPROP 2 LASTPIN (-5675 4175) $PN 6
J 0
(-5665 4185);
DISPLAY 0.489362 (-5665 4185);
PAINT MONO (-5665 4185);
FORCEPROP 2 LASTPIN (-5675 4125) $PN 41
J 0
(-5665 4135);
DISPLAY 0.489362 (-5665 4135);
PAINT MONO (-5665 4135);
FORCEPROP 2 LASTPIN (-6525 4475) $PN 38
J 2
(-6535 4485);
DISPLAY 0.489362 (-6535 4485);
PAINT MONO (-6535 4485);
FORCEPROP 2 LASTPIN (-6525 4175) $PN 37
J 2
(-6535 4185);
DISPLAY 0.489362 (-6535 4185);
PAINT MONO (-6535 4185);
FORCEPROP 2 LASTPIN (-5675 3975) $PN 5
J 0
(-5665 3985);
DISPLAY 0.489362 (-5665 3985);
PAINT MONO (-5665 3985);
FORCEPROP 2 LASTPIN (-5675 3925) $PN 7_9-20_24
J 0
(-5665 3935);
DISPLAY 0.489362 (-5665 3935);
PAINT MONO (-5665 3935);
FORCEPROP 2 LASTPIN (-5675 3875) $PN 40
J 0
(-5665 3885);
DISPLAY 0.489362 (-5665 3885);
PAINT MONO (-5665 3885);
FORCEPROP 2 LASTPIN (-5675 4575) $PN 32
J 0
(-5665 4585);
DISPLAY 0.489362 (-5665 4585);
PAINT MONO (-5665 4585);
FORCEPROP 2 LASTPIN (-6525 5125) $PN 4
J 2
(-6535 5135);
DISPLAY 0.489362 (-6535 5135);
PAINT MONO (-6535 5135);
FORCEPROP 2 LASTPIN (-6525 3875) $PN 34
J 2
(-6535 3885);
DISPLAY 0.489362 (-6535 3885);
PAINT MONO (-6535 3885);
FORCEPROP 2 LASTPIN (-6525 4375) $PN 39
J 2
(-6535 4385);
DISPLAY 0.489362 (-6535 4385);
PAINT MONO (-6535 4385);
FORCEPROP 2 LASTPIN (-5675 4475) $PN 10_19
J 0
(-5665 4485);
DISPLAY 0.489362 (-5665 4485);
PAINT MONO (-5665 4485);
FORCEPROP 2 LASTPIN (-6525 3975) $PN 36
J 2
(-6535 3985);
DISPLAY 0.489362 (-6535 3985);
PAINT MONO (-6535 3985);
FORCEPROP 2 LASTPIN (-6525 4825) $PN 3
J 2
(-6535 4835);
DISPLAY 0.489362 (-6535 4835);
PAINT MONO (-6535 4835);
FORCEPROP 2 LASTPIN (-5675 5125) $PN 25_29
J 0
(-5665 5135);
DISPLAY 0.489362 (-5665 5135);
PAINT MONO (-5665 5135);
FORCEPROP 2 LASTPIN (-5675 5075) $PN 30
J 0
(-5665 5085);
DISPLAY 0.489362 (-5665 5085);
PAINT MONO (-5665 5085);
FORCEPROP 2 LASTPIN (-5675 4225) $PN 1
J 0
(-5665 4235);
DISPLAY 0.489362 (-5665 4235);
PAINT MONO (-5665 4235);
FORCEPROP 2 LAST PART_TYPE SMLF
J 0
(-6375 5450);
DISPLAY 1.021277 (-6375 5450);
FORCEPROP 1 LAST MATERIAL IC
J 0
(-6375 5200);
DISPLAY 0.489362 (-6375 5200);
PAINT SKYBLUE (-6375 5200);
FORCEPROP 2 LAST VALUE ISL99390FRZ-TR5935
J 0
(-6375 5400);
DISPLAY 0.489362 (-6375 5400);
PAINT SKYBLUE (-6375 5400);
FORCEPROP 1 LAST PART_NUMBER AL099390004
J 0
(-6375 5275);
DISPLAY 0.489362 (-6375 5275);
PAINT SKYBLUE (-6375 5275);
FORCEPROP 2 LAST CDS_LIB pure_quanta
J 0
(-6075 4475);
DISPLAY INVISIBLE (-6075 4475);
FORCEPROP 1 LAST CDS_LMAN_SYM_OUTLINE -300,700,250,-650
J 0
(-6075 4475);
DISPLAY 0.468085 (-6075 4475);
PAINT GREEN (-6075 4475);
DISPLAY INVISIBLE (-6075 4475);
FORCEPROP 1 LAST NEEDS_NO_SIZE TRUE
J 0
(-6075 4475);
DISPLAY 0.723404 (-6075 4475);
PAINT GREEN (-6075 4475);
DISPLAY INVISIBLE (-6075 4475);
FORCEPROP 1 LAST PATH I44
J 0
(-6075 4475);
DISPLAY 0.723404 (-6075 4475);
PAINT GREEN (-6075 4475);
DISPLAY INVISIBLE (-6075 4475);
FORCEADD OFFPAGE..1
(-8075 1450);
FORCEPROP 2 LAST $XR1 201 
J 0
(-8447 1450);
DISPLAY 0.638298 (-8447 1450);
PAINT MONO (-8447 1450);
FORCEPROP 2 LAST $XR0 200 
J 0
(-8327 1450);
DISPLAY 0.638298 (-8327 1450);
PAINT MONO (-8327 1450);
FORCEPROP 2 LAST PATH I45
J 0
(-8025 1525);
DISPLAY 1.021277 (-8025 1525);
DISPLAY INVISIBLE (-8025 1525);
FORCEPROP 1 LAST OFFPAGE TRUE
J 0
(-7750 1325);
DISPLAY 0.872340 (-7750 1325);
PAINT GREEN (-7750 1325);
DISPLAY INVISIBLE (-7750 1325);
FORCEPROP 2 LAST CDS_LIB standard
J 0
(-8075 1450);
DISPLAY INVISIBLE (-8075 1450);
FORCEPROP 1 LAST COMMENT_BODY TRUE
J 0
(-7950 1350);
DISPLAY 0.872340 (-7950 1350);
PAINT GREEN (-7950 1350);
DISPLAY INVISIBLE (-7950 1350);
FORCEADD UNIVERSAL_GND..1
(-5450 825);
FORCEPROP 3 LASTPIN (-5450 875) SIG_NAME GND\g
J 0
(-5440 885);
DISPLAY 0.659574 (-5440 885);
PAINT MONO (-5440 885);
DISPLAY INVISIBLE (-5440 885);
FORCEPROP 2 LAST CDS_LIB pure_quanta_power
J 0
(-5450 825);
DISPLAY INVISIBLE (-5450 825);
FORCEPROP 1 LAST PATH I46
J 0
(-5375 825);
DISPLAY 0.872340 (-5375 825);
PAINT AQUA (-5375 825);
DISPLAY INVISIBLE (-5375 825);
FORCEPROP 1 LAST HDL_POWER GND
J 1
(-5425 750);
DISPLAY 0.872340 (-5425 750);
PAINT GREEN (-5425 750);
DISPLAY INVISIBLE (-5425 750);
FORCEADD OFFPAGE..1
(-7125 950);
FORCEPROP 2 LAST $XR0 200 
J 0
(-7407 950);
DISPLAY 0.638298 (-7407 950);
PAINT MONO (-7407 950);
FORCEPROP 2 LAST PATH I47
J 0
(-7075 1025);
DISPLAY 1.021277 (-7075 1025);
DISPLAY INVISIBLE (-7075 1025);
FORCEPROP 1 LAST OFFPAGE TRUE
J 0
(-6800 825);
DISPLAY 0.872340 (-6800 825);
PAINT GREEN (-6800 825);
DISPLAY INVISIBLE (-6800 825);
FORCEPROP 2 LAST CDS_LIB standard
J 2
(-7125 950);
DISPLAY INVISIBLE (-7125 950);
FORCEPROP 1 LAST COMMENT_BODY TRUE
J 0
(-7000 850);
DISPLAY 0.872340 (-7000 850);
PAINT GREEN (-7000 850);
DISPLAY INVISIBLE (-7000 850);
FORCEADD Q_CAP..1
(-7850 1275);
FORCEPROP 1 LAST LOCATION PC504_2
J 0
(-7800 1375);
DISPLAY 0.489362 (-7800 1375);
PAINT SKYBLUE (-7800 1375);
FORCEPROP 0 LAST $SEC 1
J 0
(-7800 1400);
DISPLAY 0.680851 (-7800 1400);
PAINT MONO (-7800 1400);
DISPLAY INVISIBLE (-7800 1400);
FORCEPROP 0 LAST CDS_SEC 1
J 0
(-7800 1400);
DISPLAY 1.021277 (-7800 1400);
DISPLAY INVISIBLE (-7800 1400);
FORCEPROP 1 LASTPIN (-7850 1375) $PN 1
J 0
(-7840 1355);
DISPLAY 0.489362 (-7840 1355);
PAINT MONO (-7840 1355);
FORCEPROP 1 LASTPIN (-7850 1175) $PN 2
J 0
(-7840 1155);
DISPLAY 0.489362 (-7840 1155);
PAINT MONO (-7840 1155);
FORCEPROP 1 LAST MATERIAL X7R
J 0
(-7800 1175);
DISPLAY 0.489362 (-7800 1175);
PAINT SKYBLUE (-7800 1175);
FORCEPROP 1 LAST TOLERANCE 10%
J 0
(-7800 1225);
DISPLAY 0.489362 (-7800 1225);
PAINT SKYBLUE (-7800 1225);
FORCEPROP 1 LAST VALUE 0.1UF
J 0
(-7800 1325);
DISPLAY 0.489362 (-7800 1325);
PAINT SKYBLUE (-7800 1325);
FORCEPROP 1 LAST PART_NUMBER CH4104K1B00
J 0
(-7800 1125);
DISPLAY 0.489362 (-7800 1125);
PAINT SKYBLUE (-7800 1125);
FORCEPROP 1 LAST VOLTAGE 25V
J 0
(-7800 1275);
DISPLAY 0.489362 (-7800 1275);
PAINT SKYBLUE (-7800 1275);
FORCEPROP 1 LAST PACK_TYPE 0402
J 0
(-7800 1075);
DISPLAY 0.489362 (-7800 1075);
PAINT SKYBLUE (-7800 1075);
FORCEPROP 2 LAST CDS_LIB pure_quanta
J 0
(-7850 1275);
DISPLAY INVISIBLE (-7850 1275);
FORCEPROP 1 LAST PATH I48
J 0
(-7800 1425);
DISPLAY 0.978723 (-7800 1425);
PAINT WHITE (-7800 1425);
DISPLAY INVISIBLE (-7800 1425);
FORCEADD UNIVERSAL_GND..1
(-7850 1000);
FORCEPROP 3 LASTPIN (-7850 1050) SIG_NAME GND\g
J 0
(-7840 1060);
DISPLAY 0.659574 (-7840 1060);
PAINT MONO (-7840 1060);
DISPLAY INVISIBLE (-7840 1060);
FORCEPROP 2 LAST CDS_LIB pure_quanta_power
J 0
(-7850 1000);
DISPLAY INVISIBLE (-7850 1000);
FORCEPROP 1 LAST PATH I49
J 0
(-7775 1000);
DISPLAY 0.872340 (-7775 1000);
PAINT AQUA (-7775 1000);
DISPLAY INVISIBLE (-7775 1000);
FORCEPROP 1 LAST HDL_POWER GND
J 1
(-7825 925);
DISPLAY 0.872340 (-7825 925);
PAINT GREEN (-7825 925);
DISPLAY INVISIBLE (-7825 925);
FORCEADD UNIVERSAL_GND..1
(-7900 3925);
FORCEPROP 3 LASTPIN (-7900 3975) SIG_NAME GND\g
J 0
(-7890 3985);
DISPLAY 0.659574 (-7890 3985);
PAINT MONO (-7890 3985);
DISPLAY INVISIBLE (-7890 3985);
FORCEPROP 2 LAST CDS_LIB pure_quanta_power
J 0
(-7900 3925);
DISPLAY INVISIBLE (-7900 3925);
FORCEPROP 1 LAST PATH I5
J 0
(-7825 3925);
DISPLAY 0.872340 (-7825 3925);
PAINT AQUA (-7825 3925);
DISPLAY INVISIBLE (-7825 3925);
FORCEPROP 1 LAST HDL_POWER GND
J 1
(-7875 3850);
DISPLAY 0.872340 (-7875 3850);
PAINT GREEN (-7875 3850);
DISPLAY INVISIBLE (-7875 3850);
FORCEADD UNIVERSAL_GND..1
(-7525 1075);
FORCEPROP 3 LASTPIN (-7525 1125) SIG_NAME GND\g
J 0
(-7515 1135);
DISPLAY 0.659574 (-7515 1135);
PAINT MONO (-7515 1135);
DISPLAY INVISIBLE (-7515 1135);
FORCEPROP 2 LAST CDS_LIB pure_quanta_power
J 0
(-7525 1075);
DISPLAY INVISIBLE (-7525 1075);
FORCEPROP 1 LAST PATH I50
J 0
(-7450 1075);
DISPLAY 0.872340 (-7450 1075);
PAINT AQUA (-7450 1075);
DISPLAY INVISIBLE (-7450 1075);
FORCEPROP 1 LAST HDL_POWER GND
J 1
(-7500 1000);
DISPLAY 0.872340 (-7500 1000);
PAINT GREEN (-7500 1000);
DISPLAY INVISIBLE (-7500 1000);
FORCEADD OFFPAGE..2
R 2
(-7150 1050);
FORCEPROP 2 LAST $XR1 200 
J 0
(-7435 1014);
DISPLAY 0.638298 (-7435 1014);
PAINT MONO (-7435 1014);
FORCEPROP 2 LAST $XR0 201 
J 0
(-7435 1050);
DISPLAY 0.638298 (-7435 1050);
PAINT MONO (-7435 1050);
FORCEPROP 2 LAST PATH I51
J 0
(-7100 1125);
DISPLAY 1.021277 (-7100 1125);
DISPLAY INVISIBLE (-7100 1125);
FORCEPROP 2 LAST CDS_LIB standard
J 0
(-7150 1050);
DISPLAY INVISIBLE (-7150 1050);
FORCEPROP 1 LAST COMMENT_BODY TRUE
J 2
(-7105 955);
DISPLAY 0.872340 (-7105 955);
PAINT GREEN (-7105 955);
DISPLAY INVISIBLE (-7105 955);
FORCEPROP 1 LAST OFFPAGE TRUE
J 2
(-7475 925);
DISPLAY 0.872340 (-7475 925);
PAINT GREEN (-7475 925);
DISPLAY INVISIBLE (-7475 925);
FORCEADD Q_RES..1
(-7200 1250);
FORCEPROP 1 LAST LOCATION PR329
J 0
(-7200 1300);
DISPLAY 0.489362 (-7200 1300);
PAINT SKYBLUE (-7200 1300);
FORCEPROP 0 LAST $SEC 1
J 0
(-7200 1325);
DISPLAY 0.680851 (-7200 1325);
PAINT MONO (-7200 1325);
DISPLAY INVISIBLE (-7200 1325);
FORCEPROP 0 LAST CDS_SEC 1
J 0
(-7200 1325);
DISPLAY 1.021277 (-7200 1325);
DISPLAY INVISIBLE (-7200 1325);
FORCEPROP 1 LASTPIN (-7300 1250) $PN 1
J 0
(-7288 1262);
DISPLAY 0.489362 (-7288 1262);
PAINT MONO (-7288 1262);
FORCEPROP 1 LASTPIN (-7100 1250) $PN 2
J 0
(-7138 1262);
DISPLAY 0.489362 (-7138 1262);
PAINT MONO (-7138 1262);
FORCEPROP 1 LAST WATTAGE 1/16W
J 0
(-7100 1150);
DISPLAY 0.489362 (-7100 1150);
PAINT SKYBLUE (-7100 1150);
FORCEPROP 1 LAST MATERIAL EMPTY
J 0
(-7500 1150);
DISPLAY 0.489362 (-7500 1150);
PAINT RED (-7500 1150);
FORCEPROP 1 LAST TOLERANCE 1%
J 0
(-7075 1275);
DISPLAY 0.489362 (-7075 1275);
PAINT SKYBLUE (-7075 1275);
FORCEPROP 1 LAST VALUE 4.87K
J 2
(-7275 1275);
DISPLAY 0.489362 (-7275 1275);
PAINT SKYBLUE (-7275 1275);
FORCEPROP 1 LAST PART_NUMBER CS24872FB07
J 0
(-7500 1200);
DISPLAY 0.489362 (-7500 1200);
PAINT SKYBLUE (-7500 1200);
FORCEPROP 1 LAST PACK_TYPE 0402LF
J 0
(-7100 1200);
DISPLAY 0.489362 (-7100 1200);
PAINT SKYBLUE (-7100 1200);
FORCEPROP 2 LAST CDS_LIB pure_quanta
J 0
(-7200 1250);
DISPLAY INVISIBLE (-7200 1250);
FORCEPROP 1 LAST PATH I52
J 0
(-7250 1400);
DISPLAY 0.978723 (-7250 1400);
PAINT WHITE (-7250 1400);
DISPLAY INVISIBLE (-7250 1400);
FORCEADD OFFPAGE..2
R 2
(-7175 1550);
FORCEPROP 2 LAST $XR0 200 
J 0
(-7460 1550);
DISPLAY 0.638298 (-7460 1550);
PAINT MONO (-7460 1550);
FORCEPROP 2 LAST PATH I55
J 0
(-7125 1625);
DISPLAY 1.021277 (-7125 1625);
DISPLAY INVISIBLE (-7125 1625);
FORCEPROP 1 LAST COMMENT_BODY TRUE
J 2
(-7130 1455);
DISPLAY 0.872340 (-7130 1455);
PAINT GREEN (-7130 1455);
DISPLAY INVISIBLE (-7130 1455);
FORCEPROP 2 LAST CDS_LIB standard
J 2
(-7175 1550);
DISPLAY INVISIBLE (-7175 1550);
FORCEPROP 1 LAST OFFPAGE TRUE
J 2
(-7500 1425);
DISPLAY 0.872340 (-7500 1425);
PAINT GREEN (-7500 1425);
DISPLAY INVISIBLE (-7500 1425);
FORCEADD UNIVERSAL_GND..1
(-7550 4000);
FORCEPROP 3 LASTPIN (-7550 4050) SIG_NAME GND\g
J 0
(-7540 4060);
DISPLAY 0.659574 (-7540 4060);
PAINT MONO (-7540 4060);
DISPLAY INVISIBLE (-7540 4060);
FORCEPROP 2 LAST CDS_LIB pure_quanta_power
J 0
(-7550 4000);
DISPLAY INVISIBLE (-7550 4000);
FORCEPROP 1 LAST PATH I6
J 0
(-7475 4000);
DISPLAY 0.872340 (-7475 4000);
PAINT AQUA (-7475 4000);
DISPLAY INVISIBLE (-7475 4000);
FORCEPROP 1 LAST HDL_POWER GND
J 1
(-7525 3925);
DISPLAY 0.872340 (-7525 3925);
PAINT GREEN (-7525 3925);
DISPLAY INVISIBLE (-7525 3925);
FORCEADD Q_RES..1
(-4675 1900);
FORCEPROP 1 LAST LOCATION PR331
J 0
(-4700 1950);
DISPLAY 0.489362 (-4700 1950);
PAINT SKYBLUE (-4700 1950);
FORCEPROP 0 LAST $SEC 1
J 0
(-4650 1975);
DISPLAY 0.680851 (-4650 1975);
PAINT MONO (-4650 1975);
DISPLAY INVISIBLE (-4650 1975);
FORCEPROP 0 LAST CDS_SEC 1
J 0
(-4650 1975);
DISPLAY 1.021277 (-4650 1975);
DISPLAY INVISIBLE (-4650 1975);
FORCEPROP 1 LASTPIN (-4775 1900) $PN 1
J 0
(-4763 1912);
DISPLAY 0.489362 (-4763 1912);
PAINT MONO (-4763 1912);
FORCEPROP 1 LASTPIN (-4575 1900) $PN 2
J 0
(-4613 1912);
DISPLAY 0.489362 (-4613 1912);
PAINT MONO (-4613 1912);
FORCEPROP 1 LAST PACK_TYPE 0402LF
J 0
(-4575 1800);
DISPLAY 0.489362 (-4575 1800);
PAINT SKYBLUE (-4575 1800);
FORCEPROP 1 LAST TOLERANCE 1%
J 0
(-4575 1925);
DISPLAY 0.489362 (-4575 1925);
PAINT SKYBLUE (-4575 1925);
FORCEPROP 1 LAST MATERIAL CHIP
J 0
(-4925 1800);
DISPLAY 0.489362 (-4925 1800);
PAINT SKYBLUE (-4925 1800);
FORCEPROP 1 LAST WATTAGE 1/16W
J 0
(-4575 1850);
DISPLAY 0.489362 (-4575 1850);
PAINT SKYBLUE (-4575 1850);
FORCEPROP 1 LAST VALUE 4.7
J 2
(-4775 1925);
DISPLAY 0.489362 (-4775 1925);
PAINT SKYBLUE (-4775 1925);
FORCEPROP 1 LAST PART_NUMBER CS-4702FB19
J 0
(-4925 1850);
DISPLAY 0.489362 (-4925 1850);
PAINT SKYBLUE (-4925 1850);
FORCEPROP 1 LAST PATH I63
J 0
(-4725 2050);
DISPLAY 0.978723 (-4725 2050);
PAINT WHITE (-4725 2050);
DISPLAY INVISIBLE (-4725 2050);
FORCEPROP 2 LAST CDS_LIB pure_quanta
J 0
(-4675 1900);
DISPLAY INVISIBLE (-4675 1900);
FORCEADD Q_CAP..1
(-3800 1775);
FORCEPROP 1 LAST LOCATION PC520
J 0
(-3750 1900);
DISPLAY 0.489362 (-3750 1900);
PAINT SKYBLUE (-3750 1900);
FORCEPROP 0 LAST $SEC 1
J 0
(-3750 1925);
DISPLAY 0.680851 (-3750 1925);
PAINT MONO (-3750 1925);
DISPLAY INVISIBLE (-3750 1925);
FORCEPROP 0 LAST CDS_SEC 1
J 0
(-3750 1925);
DISPLAY 1.021277 (-3750 1925);
DISPLAY INVISIBLE (-3750 1925);
FORCEPROP 1 LASTPIN (-3800 1875) $PN 1
J 0
(-3790 1855);
DISPLAY 0.489362 (-3790 1855);
PAINT MONO (-3790 1855);
FORCEPROP 1 LASTPIN (-3800 1675) $PN 2
J 0
(-3790 1655);
DISPLAY 0.489362 (-3790 1655);
PAINT MONO (-3790 1655);
FORCEPROP 1 LAST MATERIAL X7R
J 0
(-3750 1700);
DISPLAY 0.489362 (-3750 1700);
PAINT SKYBLUE (-3750 1700);
FORCEPROP 1 LAST TOLERANCE 10%
J 0
(-3750 1750);
DISPLAY 0.489362 (-3750 1750);
PAINT SKYBLUE (-3750 1750);
FORCEPROP 1 LAST VALUE 0.22UF
J 0
(-3750 1850);
DISPLAY 0.489362 (-3750 1850);
PAINT SKYBLUE (-3750 1850);
FORCEPROP 1 LAST PART_NUMBER CH4223K1B00
J 0
(-3750 1650);
DISPLAY 0.489362 (-3750 1650);
PAINT SKYBLUE (-3750 1650);
FORCEPROP 1 LAST VOLTAGE 16V
J 0
(-3750 1800);
DISPLAY 0.489362 (-3750 1800);
PAINT SKYBLUE (-3750 1800);
FORCEPROP 1 LAST PACK_TYPE 0402
J 0
(-3750 1600);
DISPLAY 0.489362 (-3750 1600);
PAINT SKYBLUE (-3750 1600);
FORCEPROP 2 LAST CDS_LIB pure_quanta
J 0
(-3800 1775);
DISPLAY INVISIBLE (-3800 1775);
FORCEPROP 1 LAST PATH I66
J 0
(-3750 1925);
DISPLAY 0.978723 (-3750 1925);
PAINT WHITE (-3750 1925);
DISPLAY INVISIBLE (-3750 1925);
FORCEADD Q_CAP..1
(-5350 2450);
FORCEPROP 1 LAST LOCATION PC510_2
J 0
(-5300 2550);
DISPLAY 0.489362 (-5300 2550);
PAINT SKYBLUE (-5300 2550);
FORCEPROP 0 LAST $SEC 1
J 0
(-5300 2575);
DISPLAY 0.680851 (-5300 2575);
PAINT MONO (-5300 2575);
DISPLAY INVISIBLE (-5300 2575);
FORCEPROP 0 LAST CDS_SEC 1
J 0
(-5300 2575);
DISPLAY 1.021277 (-5300 2575);
DISPLAY INVISIBLE (-5300 2575);
FORCEPROP 1 LASTPIN (-5350 2550) $PN 1
J 0
(-5340 2530);
DISPLAY 0.489362 (-5340 2530);
PAINT MONO (-5340 2530);
FORCEPROP 1 LASTPIN (-5350 2350) $PN 2
J 0
(-5340 2330);
DISPLAY 0.489362 (-5340 2330);
PAINT MONO (-5340 2330);
FORCEPROP 1 LAST MATERIAL X6S
J 0
(-5300 2350);
DISPLAY 0.489362 (-5300 2350);
PAINT SKYBLUE (-5300 2350);
FORCEPROP 1 LAST TOLERANCE 10%
J 0
(-5300 2400);
DISPLAY 0.489362 (-5300 2400);
PAINT SKYBLUE (-5300 2400);
FORCEPROP 1 LAST VALUE 1UF
J 0
(-5300 2500);
DISPLAY 0.489362 (-5300 2500);
PAINT SKYBLUE (-5300 2500);
FORCEPROP 1 LAST PART_NUMBER CH5104KEB02
J 0
(-5300 2300);
DISPLAY 0.489362 (-5300 2300);
PAINT SKYBLUE (-5300 2300);
FORCEPROP 1 LAST VOLTAGE 25V
J 0
(-5300 2450);
DISPLAY 0.489362 (-5300 2450);
PAINT SKYBLUE (-5300 2450);
FORCEPROP 1 LAST PACK_TYPE C0402
J 0
(-5300 2250);
DISPLAY 0.489362 (-5300 2250);
PAINT SKYBLUE (-5300 2250);
FORCEPROP 2 LAST CDS_LIB pure_quanta
J 0
(-5350 2450);
DISPLAY INVISIBLE (-5350 2450);
FORCEPROP 1 LAST PATH I67
J 0
(-5300 2600);
DISPLAY 0.978723 (-5300 2600);
PAINT WHITE (-5300 2600);
DISPLAY INVISIBLE (-5300 2600);
FORCEADD Q_CAP..1
(-4700 2450);
FORCEPROP 1 LAST LOCATION PC514_2
J 0
(-4650 2550);
DISPLAY 0.489362 (-4650 2550);
PAINT SKYBLUE (-4650 2550);
FORCEPROP 0 LAST $SEC 1
J 0
(-4650 2575);
DISPLAY 0.680851 (-4650 2575);
PAINT MONO (-4650 2575);
DISPLAY INVISIBLE (-4650 2575);
FORCEPROP 0 LAST CDS_SEC 1
J 0
(-4650 2575);
DISPLAY 1.021277 (-4650 2575);
DISPLAY INVISIBLE (-4650 2575);
FORCEPROP 1 LASTPIN (-4700 2550) $PN 1
J 0
(-4690 2530);
DISPLAY 0.489362 (-4690 2530);
PAINT MONO (-4690 2530);
FORCEPROP 1 LASTPIN (-4700 2350) $PN 2
J 0
(-4690 2330);
DISPLAY 0.489362 (-4690 2330);
PAINT MONO (-4690 2330);
FORCEPROP 1 LAST MATERIAL X6S
J 0
(-4650 2350);
DISPLAY 0.489362 (-4650 2350);
PAINT SKYBLUE (-4650 2350);
FORCEPROP 1 LAST TOLERANCE 10%
J 0
(-4650 2400);
DISPLAY 0.489362 (-4650 2400);
PAINT SKYBLUE (-4650 2400);
FORCEPROP 1 LAST VALUE 10UF
J 0
(-4650 2500);
DISPLAY 0.489362 (-4650 2500);
PAINT SKYBLUE (-4650 2500);
FORCEPROP 1 LAST PART_NUMBER CH6104KEA00
J 0
(-4650 2300);
DISPLAY 0.489362 (-4650 2300);
PAINT SKYBLUE (-4650 2300);
FORCEPROP 1 LAST VOLTAGE 25V
J 0
(-4650 2450);
DISPLAY 0.489362 (-4650 2450);
PAINT SKYBLUE (-4650 2450);
FORCEPROP 1 LAST PACK_TYPE C0805
J 0
(-4650 2250);
DISPLAY 0.489362 (-4650 2250);
PAINT SKYBLUE (-4650 2250);
FORCEPROP 2 LAST CDS_LIB pure_quanta
J 0
(-4700 2450);
DISPLAY INVISIBLE (-4700 2450);
FORCEPROP 1 LAST PATH I69
J 0
(-4650 2600);
DISPLAY 0.978723 (-4650 2600);
PAINT WHITE (-4650 2600);
DISPLAY INVISIBLE (-4650 2600);
FORCEADD OFFPAGE..2
R 2
(-7200 3975);
FORCEPROP 2 LAST $XR1 200 
J 0
(-7455 3939);
DISPLAY 0.638298 (-7455 3939);
PAINT MONO (-7455 3939);
FORCEPROP 2 LAST $XR0 201 
J 0
(-7455 3975);
DISPLAY 0.638298 (-7455 3975);
PAINT MONO (-7455 3975);
FORCEPROP 2 LAST PATH I7
J 0
(-7150 4050);
DISPLAY 1.021277 (-7150 4050);
DISPLAY INVISIBLE (-7150 4050);
FORCEPROP 1 LAST COMMENT_BODY TRUE
J 2
(-7155 3880);
DISPLAY 0.872340 (-7155 3880);
PAINT GREEN (-7155 3880);
DISPLAY INVISIBLE (-7155 3880);
FORCEPROP 2 LAST CDS_LIB standard
J 0
(-7200 3975);
DISPLAY INVISIBLE (-7200 3975);
FORCEPROP 1 LAST OFFPAGE TRUE
J 2
(-7525 3850);
DISPLAY 0.872340 (-7525 3850);
PAINT GREEN (-7525 3850);
DISPLAY INVISIBLE (-7525 3850);
FORCEADD Q_CAP..1
(-4400 2450);
FORCEPROP 1 LAST LOCATION PC516_2
J 0
(-4350 2550);
DISPLAY 0.489362 (-4350 2550);
PAINT SKYBLUE (-4350 2550);
FORCEPROP 0 LAST $SEC 1
J 0
(-4350 2575);
DISPLAY 0.680851 (-4350 2575);
PAINT MONO (-4350 2575);
DISPLAY INVISIBLE (-4350 2575);
FORCEPROP 0 LAST CDS_SEC 1
J 0
(-4350 2575);
DISPLAY 1.021277 (-4350 2575);
DISPLAY INVISIBLE (-4350 2575);
FORCEPROP 1 LASTPIN (-4400 2550) $PN 1
J 0
(-4390 2530);
DISPLAY 0.489362 (-4390 2530);
PAINT MONO (-4390 2530);
FORCEPROP 1 LASTPIN (-4400 2350) $PN 2
J 0
(-4390 2330);
DISPLAY 0.489362 (-4390 2330);
PAINT MONO (-4390 2330);
FORCEPROP 1 LAST MATERIAL X6S
J 0
(-4350 2350);
DISPLAY 0.489362 (-4350 2350);
PAINT SKYBLUE (-4350 2350);
FORCEPROP 1 LAST TOLERANCE 10%
J 0
(-4350 2400);
DISPLAY 0.489362 (-4350 2400);
PAINT SKYBLUE (-4350 2400);
FORCEPROP 1 LAST VALUE 10UF
J 0
(-4350 2500);
DISPLAY 0.489362 (-4350 2500);
PAINT SKYBLUE (-4350 2500);
FORCEPROP 1 LAST PART_NUMBER CH6104KEA00
J 0
(-4350 2300);
DISPLAY 0.489362 (-4350 2300);
PAINT SKYBLUE (-4350 2300);
FORCEPROP 1 LAST VOLTAGE 25V
J 0
(-4350 2450);
DISPLAY 0.489362 (-4350 2450);
PAINT SKYBLUE (-4350 2450);
FORCEPROP 1 LAST PACK_TYPE C0805
J 0
(-4350 2250);
DISPLAY 0.489362 (-4350 2250);
PAINT SKYBLUE (-4350 2250);
FORCEPROP 2 LAST CDS_LIB pure_quanta
J 0
(-4400 2450);
DISPLAY INVISIBLE (-4400 2450);
FORCEPROP 1 LAST PATH I70
J 0
(-4350 2600);
DISPLAY 0.978723 (-4350 2600);
PAINT WHITE (-4350 2600);
DISPLAY INVISIBLE (-4350 2600);
FORCEADD UNIVERSAL_GND..1
(-3750 2150);
FORCEPROP 3 LASTPIN (-3750 2200) SIG_NAME GND\g
J 0
(-3740 2210);
DISPLAY 0.659574 (-3740 2210);
PAINT MONO (-3740 2210);
DISPLAY INVISIBLE (-3740 2210);
FORCEPROP 2 LAST CDS_LIB pure_quanta_power
J 0
(-3750 2150);
DISPLAY INVISIBLE (-3750 2150);
FORCEPROP 1 LAST PATH I71
J 0
(-3675 2150);
DISPLAY 0.872340 (-3675 2150);
PAINT AQUA (-3675 2150);
DISPLAY INVISIBLE (-3675 2150);
FORCEPROP 1 LAST HDL_POWER GND
J 1
(-3725 2075);
DISPLAY 0.872340 (-3725 2075);
PAINT GREEN (-3725 2075);
DISPLAY INVISIBLE (-3725 2075);
FORCEADD VCC_CORE..1
(-3750 2725);
FORCEPROP 3 LASTPIN (-3750 2675) SIG_NAME SW_P12V_STBY_PVDD11_S3_P1_FLT\g
J 0
(-3740 2685);
DISPLAY 0.659574 (-3740 2685);
PAINT MONO (-3740 2685);
DISPLAY INVISIBLE (-3740 2685);
FORCEPROP 1 LAST HDL_POWER SW_P12V_STBY_PVDD11_S3_P1_FLT
J 1
(-3750 2775);
DISPLAY 0.489362 (-3750 2775);
PAINT GREEN (-3750 2775);
FORCEPROP 2 LAST CDS_LIB pure_quanta_power
J 0
(-3750 2725);
DISPLAY INVISIBLE (-3750 2725);
FORCEPROP 1 LAST PATH I73
J 0
(-3700 2750);
DISPLAY 0.872340 (-3700 2750);
PAINT AQUA (-3700 2750);
DISPLAY INVISIBLE (-3700 2750);
FORCEADD Q_CAP..1
(-2400 1375);
FORCEPROP 1 LAST LOCATION PC523_2
J 0
(-2350 1475);
DISPLAY 0.489362 (-2350 1475);
PAINT SKYBLUE (-2350 1475);
FORCEPROP 0 LAST $SEC 1
J 0
(-2350 1500);
DISPLAY 0.680851 (-2350 1500);
PAINT MONO (-2350 1500);
DISPLAY INVISIBLE (-2350 1500);
FORCEPROP 0 LAST CDS_SEC 1
J 0
(-2350 1500);
DISPLAY 1.021277 (-2350 1500);
DISPLAY INVISIBLE (-2350 1500);
FORCEPROP 1 LASTPIN (-2400 1475) $PN 1
J 0
(-2390 1455);
DISPLAY 0.489362 (-2390 1455);
PAINT MONO (-2390 1455);
FORCEPROP 1 LASTPIN (-2400 1275) $PN 2
J 0
(-2390 1255);
DISPLAY 0.489362 (-2390 1255);
PAINT MONO (-2390 1255);
FORCEPROP 1 LAST MATERIAL X6S
J 0
(-2350 1275);
DISPLAY 0.489362 (-2350 1275);
PAINT SKYBLUE (-2350 1275);
FORCEPROP 1 LAST TOLERANCE 20%
J 0
(-2350 1325);
DISPLAY 0.489362 (-2350 1325);
PAINT SKYBLUE (-2350 1325);
FORCEPROP 1 LAST VALUE 22UF
J 0
(-2350 1425);
DISPLAY 0.489362 (-2350 1425);
PAINT SKYBLUE (-2350 1425);
FORCEPROP 1 LAST PART_NUMBER TMP_QCH622KMEA01
J 0
(-2350 1225);
DISPLAY 0.489362 (-2350 1225);
PAINT SKYBLUE (-2350 1225);
FORCEPROP 1 LAST VOLTAGE 4V
J 0
(-2350 1375);
DISPLAY 0.489362 (-2350 1375);
PAINT SKYBLUE (-2350 1375);
FORCEPROP 1 LAST PACK_TYPE 0805
J 0
(-2350 1175);
DISPLAY 0.489362 (-2350 1175);
PAINT SKYBLUE (-2350 1175);
FORCEPROP 2 LAST CDS_LIB pure_quanta
J 0
(-2400 1375);
DISPLAY INVISIBLE (-2400 1375);
FORCEPROP 1 LAST PATH I79
J 0
(-2350 1525);
DISPLAY 0.978723 (-2350 1525);
PAINT WHITE (-2350 1525);
DISPLAY INVISIBLE (-2350 1525);
FORCEADD UNIVERSAL_GND..1
(-1975 1025);
FORCEPROP 3 LASTPIN (-1975 1075) SIG_NAME GND\g
J 0
(-1965 1085);
DISPLAY 0.659574 (-1965 1085);
PAINT MONO (-1965 1085);
DISPLAY INVISIBLE (-1965 1085);
FORCEPROP 2 LAST CDS_LIB pure_quanta_power
J 0
(-1975 1025);
DISPLAY INVISIBLE (-1975 1025);
FORCEPROP 1 LAST PATH I80
J 0
(-1900 1025);
DISPLAY 0.872340 (-1900 1025);
PAINT AQUA (-1900 1025);
DISPLAY INVISIBLE (-1900 1025);
FORCEPROP 1 LAST HDL_POWER GND
J 1
(-1950 950);
DISPLAY 0.872340 (-1950 950);
PAINT GREEN (-1950 950);
DISPLAY INVISIBLE (-1950 950);
FORCEADD Q_CAP..1
(-1975 1375);
FORCEPROP 1 LAST LOCATION PC527_2
J 0
(-1925 1475);
DISPLAY 0.489362 (-1925 1475);
PAINT SKYBLUE (-1925 1475);
FORCEPROP 0 LAST $SEC 1
J 0
(-1925 1500);
DISPLAY 0.680851 (-1925 1500);
PAINT MONO (-1925 1500);
DISPLAY INVISIBLE (-1925 1500);
FORCEPROP 0 LAST CDS_SEC 1
J 0
(-1925 1500);
DISPLAY 1.021277 (-1925 1500);
DISPLAY INVISIBLE (-1925 1500);
FORCEPROP 1 LASTPIN (-1975 1475) $PN 1
J 0
(-1965 1455);
DISPLAY 0.489362 (-1965 1455);
PAINT MONO (-1965 1455);
FORCEPROP 1 LASTPIN (-1975 1275) $PN 2
J 0
(-1965 1255);
DISPLAY 0.489362 (-1965 1255);
PAINT MONO (-1965 1255);
FORCEPROP 1 LAST MATERIAL X6S
J 0
(-1925 1275);
DISPLAY 0.489362 (-1925 1275);
PAINT SKYBLUE (-1925 1275);
FORCEPROP 1 LAST TOLERANCE 20%
J 0
(-1925 1325);
DISPLAY 0.489362 (-1925 1325);
PAINT SKYBLUE (-1925 1325);
FORCEPROP 1 LAST VALUE 22UF
J 0
(-1925 1425);
DISPLAY 0.489362 (-1925 1425);
PAINT SKYBLUE (-1925 1425);
FORCEPROP 1 LAST PART_NUMBER TMP_QCH622KMEA01
J 0
(-1925 1225);
DISPLAY 0.489362 (-1925 1225);
PAINT SKYBLUE (-1925 1225);
FORCEPROP 1 LAST VOLTAGE 4V
J 0
(-1925 1375);
DISPLAY 0.489362 (-1925 1375);
PAINT SKYBLUE (-1925 1375);
FORCEPROP 1 LAST PACK_TYPE 0805
J 0
(-1925 1175);
DISPLAY 0.489362 (-1925 1175);
PAINT SKYBLUE (-1925 1175);
FORCEPROP 2 LAST CDS_LIB pure_quanta
J 0
(-1975 1375);
DISPLAY INVISIBLE (-1975 1375);
FORCEPROP 1 LAST PATH I81
J 0
(-1925 1525);
DISPLAY 0.978723 (-1925 1525);
PAINT WHITE (-1925 1525);
DISPLAY INVISIBLE (-1925 1525);
FORCEADD VCC_CORE..1
(-1975 1700);
FORCEPROP 3 LASTPIN (-1975 1650) SIG_NAME PVDD11_S3_P1\g
J 0
(-1965 1660);
DISPLAY 0.659574 (-1965 1660);
PAINT MONO (-1965 1660);
DISPLAY INVISIBLE (-1965 1660);
FORCEPROP 1 LAST HDL_POWER PVDD11_S3_P1
J 1
(-1975 1750);
DISPLAY 0.489362 (-1975 1750);
PAINT GREEN (-1975 1750);
FORCEPROP 2 LAST CDS_LIB pure_quanta_power
J 0
(-1975 1700);
DISPLAY INVISIBLE (-1975 1700);
FORCEPROP 1 LAST PATH I82
J 0
(-1925 1725);
DISPLAY 0.872340 (-1925 1725);
PAINT AQUA (-1925 1725);
DISPLAY INVISIBLE (-1925 1725);
FORCEADD ISL99390FRZTR5935..1
(-6025 1550);
FORCEPROP 1 LAST LOCATION PU45
J 0
(-6325 2425);
DISPLAY 0.489362 (-6325 2425);
PAINT SKYBLUE (-6325 2425);
FORCEPROP 2 LAST $SEC 1
J 0
(-6325 2575);
DISPLAY 0.680851 (-6325 2575);
PAINT MONO (-6325 2575);
DISPLAY INVISIBLE (-6325 2575);
FORCEPROP 2 LAST CDS_SEC 1
J 0
(-6325 2575);
DISPLAY 1.021277 (-6325 2575);
DISPLAY INVISIBLE (-6325 2575);
FORCEPROP 2 LASTPIN (-5625 1100) $PN 2
J 0
(-5615 1110);
DISPLAY 0.489362 (-5615 1110);
PAINT MONO (-5615 1110);
FORCEPROP 2 LASTPIN (-5625 1900) $PN 33
J 0
(-5615 1910);
DISPLAY 0.489362 (-5615 1910);
PAINT MONO (-5615 1910);
FORCEPROP 2 LASTPIN (-6475 1300) $PN 31
J 2
(-6485 1310);
DISPLAY 0.489362 (-6485 1310);
PAINT MONO (-6485 1310);
FORCEPROP 2 LASTPIN (-6475 1700) $PN 35
J 2
(-6485 1710);
DISPLAY 0.489362 (-6485 1710);
PAINT MONO (-6485 1710);
FORCEPROP 2 LASTPIN (-5625 1250) $PN 6
J 0
(-5615 1260);
DISPLAY 0.489362 (-5615 1260);
PAINT MONO (-5615 1260);
FORCEPROP 2 LASTPIN (-5625 1200) $PN 41
J 0
(-5615 1210);
DISPLAY 0.489362 (-5615 1210);
PAINT MONO (-5615 1210);
FORCEPROP 2 LASTPIN (-6475 1550) $PN 38
J 2
(-6485 1560);
DISPLAY 0.489362 (-6485 1560);
PAINT MONO (-6485 1560);
FORCEPROP 2 LASTPIN (-6475 1250) $PN 37
J 2
(-6485 1260);
DISPLAY 0.489362 (-6485 1260);
PAINT MONO (-6485 1260);
FORCEPROP 2 LASTPIN (-5625 1050) $PN 5
J 0
(-5615 1060);
DISPLAY 0.489362 (-5615 1060);
PAINT MONO (-5615 1060);
FORCEPROP 2 LASTPIN (-5625 1000) $PN 7_9-20_24
J 0
(-5615 1010);
DISPLAY 0.489362 (-5615 1010);
PAINT MONO (-5615 1010);
FORCEPROP 2 LASTPIN (-5625 950) $PN 40
J 0
(-5615 960);
DISPLAY 0.489362 (-5615 960);
PAINT MONO (-5615 960);
FORCEPROP 2 LASTPIN (-5625 1650) $PN 32
J 0
(-5615 1660);
DISPLAY 0.489362 (-5615 1660);
PAINT MONO (-5615 1660);
FORCEPROP 2 LASTPIN (-6475 2200) $PN 4
J 2
(-6485 2210);
DISPLAY 0.489362 (-6485 2210);
PAINT MONO (-6485 2210);
FORCEPROP 2 LASTPIN (-6475 950) $PN 34
J 2
(-6485 960);
DISPLAY 0.489362 (-6485 960);
PAINT MONO (-6485 960);
FORCEPROP 2 LASTPIN (-6475 1450) $PN 39
J 2
(-6485 1460);
DISPLAY 0.489362 (-6485 1460);
PAINT MONO (-6485 1460);
FORCEPROP 2 LASTPIN (-5625 1550) $PN 10_19
J 0
(-5615 1560);
DISPLAY 0.489362 (-5615 1560);
PAINT MONO (-5615 1560);
FORCEPROP 2 LASTPIN (-6475 1050) $PN 36
J 2
(-6485 1060);
DISPLAY 0.489362 (-6485 1060);
PAINT MONO (-6485 1060);
FORCEPROP 2 LASTPIN (-6475 1900) $PN 3
J 2
(-6485 1910);
DISPLAY 0.489362 (-6485 1910);
PAINT MONO (-6485 1910);
FORCEPROP 2 LASTPIN (-5625 2200) $PN 25_29
J 0
(-5615 2210);
DISPLAY 0.489362 (-5615 2210);
PAINT MONO (-5615 2210);
FORCEPROP 2 LASTPIN (-5625 2150) $PN 30
J 0
(-5615 2160);
DISPLAY 0.489362 (-5615 2160);
PAINT MONO (-5615 2160);
FORCEPROP 2 LASTPIN (-5625 1300) $PN 1
J 0
(-5615 1310);
DISPLAY 0.489362 (-5615 1310);
PAINT MONO (-5615 1310);
FORCEPROP 2 LAST PART_TYPE SMLF
J 0
(-6325 2525);
DISPLAY 1.021277 (-6325 2525);
FORCEPROP 1 LAST MATERIAL IC
J 0
(-6325 2275);
DISPLAY 0.489362 (-6325 2275);
PAINT SKYBLUE (-6325 2275);
FORCEPROP 2 LAST VALUE ISL99390FRZ-TR5935
J 0
(-6325 2475);
DISPLAY 0.489362 (-6325 2475);
PAINT SKYBLUE (-6325 2475);
FORCEPROP 1 LAST PART_NUMBER AL099390004
J 0
(-6325 2350);
DISPLAY 0.489362 (-6325 2350);
PAINT SKYBLUE (-6325 2350);
FORCEPROP 1 LAST NEEDS_NO_SIZE TRUE
J 0
(-6025 1550);
DISPLAY 0.723404 (-6025 1550);
PAINT GREEN (-6025 1550);
DISPLAY INVISIBLE (-6025 1550);
FORCEPROP 1 LAST CDS_LMAN_SYM_OUTLINE -300,700,250,-650
J 0
(-6025 1550);
DISPLAY 0.468085 (-6025 1550);
PAINT GREEN (-6025 1550);
DISPLAY INVISIBLE (-6025 1550);
FORCEPROP 2 LAST CDS_LIB pure_quanta
J 0
(-6025 1550);
DISPLAY INVISIBLE (-6025 1550);
FORCEPROP 1 LAST PATH I84
J 0
(-6025 1550);
DISPLAY 0.723404 (-6025 1550);
PAINT GREEN (-6025 1550);
DISPLAY INVISIBLE (-6025 1550);
FORCEADD UNIVERSAL_GND..1
(-2900 2300);
FORCEPROP 3 LASTPIN (-2900 2350) SIG_NAME GND\g
J 0
(-2890 2360);
DISPLAY 0.659574 (-2890 2360);
PAINT MONO (-2890 2360);
DISPLAY INVISIBLE (-2890 2360);
FORCEPROP 2 LAST CDS_LIB pure_quanta_power
J 0
(-2900 2300);
DISPLAY INVISIBLE (-2900 2300);
FORCEPROP 1 LAST PATH I90
J 0
(-2825 2300);
DISPLAY 0.872340 (-2825 2300);
PAINT AQUA (-2825 2300);
DISPLAY INVISIBLE (-2825 2300);
FORCEPROP 1 LAST HDL_POWER GND
J 1
(-2875 2225);
DISPLAY 0.872340 (-2875 2225);
PAINT GREEN (-2875 2225);
DISPLAY INVISIBLE (-2875 2225);
FORCEADD VCC_CORE..1
(-2900 2875);
FORCEPROP 3 LASTPIN (-2900 2825) SIG_NAME PVDD11_S3_P1\g
J 0
(-2890 2835);
DISPLAY 0.659574 (-2890 2835);
PAINT MONO (-2890 2835);
DISPLAY INVISIBLE (-2890 2835);
FORCEPROP 1 LAST HDL_POWER PVDD11_S3_P1
J 1
(-2900 2925);
DISPLAY 0.489362 (-2900 2925);
PAINT GREEN (-2900 2925);
FORCEPROP 2 LAST CDS_LIB pure_quanta_power
J 0
(-2900 2875);
DISPLAY INVISIBLE (-2900 2875);
FORCEPROP 1 LAST PATH I93
J 0
(-2850 2900);
DISPLAY 0.872340 (-2850 2900);
PAINT AQUA (-2850 2900);
DISPLAY INVISIBLE (-2850 2900);
FORCEADD Q_CAPP..1
(-2900 2625);
FORCEPROP 1 LAST LOCATION PC525
J 0
(-2850 2725);
DISPLAY 0.489362 (-2850 2725);
PAINT SKYBLUE (-2850 2725);
FORCEPROP 0 LAST $SEC 1
J 0
(-2850 2750);
DISPLAY 0.680851 (-2850 2750);
PAINT MONO (-2850 2750);
DISPLAY INVISIBLE (-2850 2750);
FORCEPROP 0 LAST CDS_SEC 1
J 0
(-2850 2750);
DISPLAY 1.021277 (-2850 2750);
DISPLAY INVISIBLE (-2850 2750);
FORCEPROP 1 LASTPIN (-2900 2725) $PN 1
J 0
(-2890 2710);
DISPLAY 0.489362 (-2890 2710);
PAINT MONO (-2890 2710);
FORCEPROP 1 LASTPIN (-2900 2525) $PN 2
J 0
(-2890 2510);
DISPLAY 0.489362 (-2890 2510);
PAINT MONO (-2890 2510);
FORCEPROP 1 LAST MATERIAL SPCAP
J 0
(-2850 2525);
DISPLAY 0.489362 (-2850 2525);
PAINT SKYBLUE (-2850 2525);
FORCEPROP 1 LAST TOLERANCE 20%
J 0
(-2850 2625);
DISPLAY 0.489362 (-2850 2625);
PAINT SKYBLUE (-2850 2625);
FORCEPROP 1 LAST VALUE 470UF
J 0
(-2850 2675);
DISPLAY 0.489362 (-2850 2675);
PAINT SKYBLUE (-2850 2675);
FORCEPROP 1 LAST PART_NUMBER CH747LM8825
J 0
(-2850 2425);
DISPLAY 0.489362 (-2850 2425);
PAINT SKYBLUE (-2850 2425);
FORCEPROP 1 LAST VOLTAGE 2.5V
J 0
(-2850 2575);
DISPLAY 0.489362 (-2850 2575);
PAINT SKYBLUE (-2850 2575);
FORCEPROP 1 LAST PACK_TYPE SMLF
J 0
(-2850 2475);
DISPLAY 0.489362 (-2850 2475);
PAINT SKYBLUE (-2850 2475);
FORCEPROP 2 LAST CDS_LIB pure_quanta
J 0
(-2900 2625);
DISPLAY INVISIBLE (-2900 2625);
FORCEPROP 1 LAST PATH I98
J 0
(-2850 2775);
DISPLAY 0.978723 (-2850 2775);
DISPLAY INVISIBLE (-2850 2775);
FORCEADD DNS..1
(-4650 4275);
PAINT RED (-4650 4275);
FORCEPROP 2 LAST CDS_LIB mstr_misc
J 0
(-4650 4275);
DISPLAY INVISIBLE (-4650 4275);
FORCEPROP 1 LAST COMMENT_BODY TRUE
R 1
J 0
(-4575 4050);
DISPLAY 0.872340 (-4575 4050);
PAINT GREEN (-4575 4050);
DISPLAY INVISIBLE (-4575 4050);
FORCEADD DNS..1
(-7200 1225);
PAINT RED (-7200 1225);
FORCEPROP 2 LAST CDS_LIB mstr_misc
J 0
(-7200 1225);
DISPLAY INVISIBLE (-7200 1225);
FORCEPROP 1 LAST COMMENT_BODY TRUE
R 1
J 0
(-7125 1000);
DISPLAY 0.872340 (-7125 1000);
PAINT GREEN (-7125 1000);
DISPLAY INVISIBLE (-7125 1000);
FORCEADD DNS..1
(-4650 3750);
PAINT RED (-4650 3750);
FORCEPROP 2 LAST CDS_LIB mstr_misc
J 0
(-4650 3750);
DISPLAY INVISIBLE (-4650 3750);
FORCEPROP 1 LAST COMMENT_BODY TRUE
R 1
J 0
(-4575 3525);
DISPLAY 0.872340 (-4575 3525);
PAINT GREEN (-4575 3525);
DISPLAY INVISIBLE (-4575 3525);
FORCEADD DNS..1
(-7225 4150);
PAINT RED (-7225 4150);
FORCEPROP 2 LAST CDS_LIB mstr_misc
J 0
(-7225 4150);
DISPLAY INVISIBLE (-7225 4150);
FORCEPROP 1 LAST COMMENT_BODY TRUE
R 1
J 0
(-7150 3925);
DISPLAY 0.872340 (-7150 3925);
PAINT GREEN (-7150 3925);
DISPLAY INVISIBLE (-7150 3925);
FORCEADD DNS..1
(-4600 875);
PAINT RED (-4600 875);
FORCEPROP 2 LAST CDS_LIB mstr_misc
J 0
(-4600 875);
DISPLAY INVISIBLE (-4600 875);
FORCEPROP 1 LAST COMMENT_BODY TRUE
R 1
J 0
(-4525 650);
DISPLAY 0.872340 (-4525 650);
PAINT GREEN (-4525 650);
DISPLAY INVISIBLE (-4525 650);
FORCEADD DNS..1
(-4600 1375);
PAINT RED (-4600 1375);
FORCEPROP 2 LAST CDS_LIB mstr_misc
J 0
(-4600 1375);
DISPLAY INVISIBLE (-4600 1375);
FORCEPROP 1 LAST COMMENT_BODY TRUE
R 1
J 0
(-4525 1150);
DISPLAY 0.872340 (-4525 1150);
PAINT GREEN (-4525 1150);
DISPLAY INVISIBLE (-4525 1150);
FORCEADD DNS..1
(-8075 5750);
PAINT RED (-8075 5750);
FORCEPROP 2 LAST CDS_LIB mstr_misc
J 0
(-8075 5750);
DISPLAY INVISIBLE (-8075 5750);
FORCEPROP 1 LAST COMMENT_BODY TRUE
R 1
J 0
(-8000 5525);
DISPLAY 0.872340 (-8000 5525);
PAINT GREEN (-8000 5525);
DISPLAY INVISIBLE (-8000 5525);
FORCEADD QUANTA_TITLE_BLOCK_C..1
(-100 -250);
FORCEPROP 0 LAST CDS_CON_LAST_MODIFIED Fri Mar 11 14:53:22 2022
J 0
(-1985 -235);
DISPLAY INVISIBLE (-1985 -235);
FORCEPROP 1 LAST CUSTOM_TXT_CDS <CON_LAST_MODIFIED>
J 0
(-1985 -235);
DISPLAY 0.978723 (-1985 -235);
FORCEPROP 2 LAST CUSTOM_TXT_CDS <XR_PAGE_TITLE>
J 0
(-7990 5000);
DISPLAY 0.638298 (-7990 5000);
PAINT PINK (-7990 5000);
DISPLAY INVISIBLE (-7990 5000);
FORCEPROP 1 LAST CUSTOM_TXT_CDS <NAME_2>
J 0
(-3275 -200);
FORCEPROP 1 LAST CUSTOM_TXT_CDS <NAME_1>
J 0
(-3275 -75);
FORCEPROP 1 LAST CUSTOM_TXT_CDS <Q_NUMBER>
J 0
(-1503 -147);
DISPLAY 1.212766 (-1503 -147);
FORCEPROP 1 LAST CUSTOM_TXT_CDS <Q_PROJ>
J 0
(-2482 -148);
DISPLAY 1.212766 (-2482 -148);
FORCEPROP 1 LAST CUSTOM_TXT_CDS <Q_REV>
J 0
(-284 -147);
DISPLAY 1.212766 (-284 -147);
FORCEPROP 1 LAST CUSTOM_TXT_CDS <CON_PAGE_NUM> OF <CON_TOTAL_PAGES>
J 0
(-546 -232);
DISPLAY 0.978723 (-546 -232);
FORCEPROP 1 LAST Q_DEPT BU9
J 1
(-3863 -201);
DISPLAY 1.957447 (-3863 -201);
PAINT GREEN (-3863 -201);
FORCEPROP 1 LAST Q_TITLE PVDD11_S3_P1 VR PHASE 1&2
J 0
(-9400 -200);
DISPLAY 2.446809 (-9400 -200);
PAINT GREEN (-9400 -200);
FORCEPROP 2 LAST PAGE_BORDER TRUE
J 0
(-7990 5000);
DISPLAY 0.638298 (-7990 5000);
PAINT PINK (-7990 5000);
DISPLAY INVISIBLE (-7990 5000);
FORCEPROP 1 LAST CDS_LMAN_SYM_OUTLINE -9475,6775,100,-125
J 0
(-100 -250);
DISPLAY 0.468085 (-100 -250);
PAINT GREEN (-100 -250);
DISPLAY INVISIBLE (-100 -250);
FORCEPROP 2 LAST CDS_LIB pure_quanta
J 0
(-100 -250);
DISPLAY INVISIBLE (-100 -250);
FORCEPROP 1 LAST COMMENT_BODY TRUE
J 0
(-88 -263);
DISPLAY 0.978723 (-88 -263);
PAINT GREEN (-88 -263);
DISPLAY INVISIBLE (-88 -263);
FORCEPROP 2 LAST CDS_XR_PAGE_TITLE CR-201 : @T6G_MB_LIB.T6G(SCH_1):PAGE201
J 0
(-7990 5000);
DISPLAY 0.638298 (-7990 5000);
PAINT PINK (-7990 5000);
DISPLAY INVISIBLE (-7990 5000);
WIRE 16 -1 (-7800 4700)(-7800 4650);
WIRE 16 -1 (-7450 5275)(-7450 5150);
WIRE 16 -1 (-7800 1775)(-7800 1725);
WIRE 16 -1 (-7450 2350)(-7450 2225);
WIRE 16 -1 (-4625 3650)(-4625 3575);
WIRE 16 -1 (-4575 775)(-4575 700);
WIRE 16 -1 (-8450 5900)(-8450 5850);
WIRE 16 -1 (-8100 5900)(-8100 5850);
WIRE 16 -1 (-7850 1175)(-7850 1050);
WIRE 16 -1 (-7900 4100)(-7900 3975);
WIRE 16 -1 (-7300 1250)(-7525 1250);
WIRE 16 -1 (-7525 1250)(-7525 1125);
WIRE 16 -1 (-7325 4175)(-7550 4175);
WIRE 16 -1 (-7550 4175)(-7550 4050);
WIRE 17 273 (-3200 3025)(-400 3025);
WIRE 17 273 (-3200 2200)(-3200 3025);
WIRE 17 273 (-400 3025)(-400 2200);
WIRE 17 273 (-3200 2200)(-400 2200);
WIRE 16 -1 (-2575 4475)(-2575 3350);
WIRE 16 -1 (-2575 4475)(-2325 4475);
WIRE 16 -1 (-2575 4475)(-3250 4475);
WIRE 16 -1 (-2575 3350)(-3500 3350);
WIRE 16 -1 (-2000 4475)(-2325 4475);
WIRE 16 -1 (-2325 4400)(-2325 4475);
WIRE 16 -1 (-2000 4475)(-1575 4475);
WIRE 16 -1 (-2000 4475)(-2000 4400);
WIRE 16 -1 (-1150 4475)(-1575 4475);
WIRE 16 -1 (-1575 4475)(-1575 4400);
WIRE 16 -1 (-1150 4550)(-1150 4475);
WIRE 16 -1 (-1150 4475)(-1150 4375);
WIRE 16 -1 (-3800 1675)(-3800 1650);
WIRE 16 -1 (-3800 1650)(-5625 1650);
FORCEPROP 2 LAST SIG_NAME SW_PVDD11_S3_P1_PH2
J 0
(-5485 1660);
DISPLAY 0.489362 (-5485 1660);
FORCEPROP 2 LASTPROP $XRERR UNIQUE?
J 0
(-5725 1660);
DISPLAY 0.638298 (-5725 1660);
PAINT MONO (-5725 1660);
DISPLAY INVISIBLE (-5725 1660);
WIRE 16 -1 (-4575 1550)(-3400 1550);
WIRE 16 -1 (-4575 1550)(-4575 1475);
WIRE 16 -1 (-5625 1550)(-4575 1550);
FORCEPROP 2 LAST SIG_NAME SW_PVDD11_S3_P1_SW2
J 0
(-5485 1560);
DISPLAY 0.489362 (-5485 1560);
FORCEPROP 2 LASTPROP $XRERR UNIQUE?
J 0
(-5725 1560);
DISPLAY 0.638298 (-5725 1560);
PAINT MONO (-5725 1560);
DISPLAY INVISIBLE (-5725 1560);
WIRE 16 -1 (-3900 4600)(-3900 4575);
WIRE 16 -1 (-3900 4575)(-5675 4575);
FORCEPROP 2 LAST SIG_NAME SW_PVDD11_S3_P1_PH1
J 0
(-5535 4585);
DISPLAY 0.489362 (-5535 4585);
FORCEPROP 2 LASTPROP $XRERR UNIQUE?
J 0
(-5775 4585);
DISPLAY 0.638298 (-5775 4585);
PAINT MONO (-5775 4585);
DISPLAY INVISIBLE (-5775 4585);
WIRE 16 -1 (-5675 4475)(-4625 4475);
FORCEPROP 2 LAST SIG_NAME SW_PVDD11_S3_P1_SW1
J 0
(-5535 4485);
DISPLAY 0.489362 (-5535 4485);
FORCEPROP 2 LASTPROP $XRERR UNIQUE?
J 0
(-5775 4485);
DISPLAY 0.638298 (-5775 4485);
PAINT MONO (-5775 4485);
DISPLAY INVISIBLE (-5775 4485);
WIRE 16 -1 (-4625 4475)(-3450 4475);
WIRE 16 -1 (-4625 4375)(-4625 4475);
WIRE 16 -1 (-8450 5650)(-8450 5575);
WIRE 16 -1 (-8450 5575)(-8100 5575);
WIRE 16 -1 (-8100 5650)(-8100 5575);
WIRE 16 -1 (-8100 5575)(-7800 5575);
WIRE 16 -1 (-7625 5575)(-7800 5575);
WIRE 16 -1 (-7800 5450)(-7800 5575);
WIRE 16 -1 (-7625 5900)(-7625 5575);
WIRE 16 -1 (-7625 5575)(-7450 5575);
WIRE 16 -1 (-6875 5575)(-7450 5575);
WIRE 16 -1 (-7450 5475)(-7450 5575);
WIRE 16 -1 (-6875 5125)(-6875 5575);
WIRE 16 -1 (-6875 5125)(-6525 5125);
WIRE 16 -1 (-8025 1450)(-7850 1450);
WIRE 16 -1 (-6475 1450)(-7850 1450);
FORCEPROP 2 LAST SIG_NAME PVDD11_S3_P1_VCCS
J 2
(-6560 1460);
DISPLAY 0.489362 (-6560 1460);
WIRE 16 -1 (-7850 1375)(-7850 1450);
WIRE 16 -1 (-6475 950)(-7075 950);
FORCEPROP 2 LAST SIG_NAME PVDD11_S3_P1_PWM2
J 2
(-6560 960);
DISPLAY 0.489362 (-6560 960);
WIRE 16 -1 (-7075 1700)(-6475 1700);
WIRE 16 -1 (-7075 1900)(-7075 1700);
WIRE 16 -1 (-7075 2050)(-7075 1900);
FORCEPROP 2 LAST SIG_NAME PVDD11_S3_P1_VCC2
J 2
(-6635 1910);
DISPLAY 0.489362 (-6635 1910);
FORCEPROP 2 LASTPROP $XRERR UNIQUE?
J 0
(-6875 1910);
DISPLAY 0.638298 (-6875 1910);
PAINT MONO (-6875 1910);
DISPLAY INVISIBLE (-6875 1910);
WIRE 16 -1 (-6475 1900)(-7075 1900);
WIRE 16 -1 (-7075 2050)(-7800 2050);
WIRE 16 -1 (-7800 2325)(-7800 2050);
WIRE 16 -1 (-7800 2050)(-7800 1975);
WIRE 16 -1 (-7100 1250)(-6475 1250);
FORCEPROP 2 LAST SIG_NAME PVDD11_S3_P1_LSET2
J 2
(-6560 1260);
DISPLAY 0.489362 (-6560 1260);
FORCEPROP 2 LASTPROP $XRERR UNIQUE?
J 0
(-6800 1260);
DISPLAY 0.638298 (-6800 1260);
PAINT MONO (-6800 1260);
DISPLAY INVISIBLE (-6800 1260);
WIRE 16 -1 (-6475 1300)(-6925 1300);
FORCEPROP 2 LAST SIG_NAME NC_PVDD11_S3_P1_DNC2
J 2
(-6560 1310);
DISPLAY 0.489362 (-6560 1310);
FORCEPROP 2 LASTPROP $XRERR UNIQUE?
J 0
(-7165 1300);
DISPLAY 0.638298 (-7165 1300);
PAINT MONO (-7165 1300);
DISPLAY INVISIBLE (-7165 1300);
WIRE 16 -1 (-6475 1050)(-7100 1050);
FORCEPROP 2 LAST SIG_NAME PVDD11_S3_P1_TEMP0
J 2
(-6560 1060);
DISPLAY 0.489362 (-6560 1060);
WIRE 16 -1 (-6475 1550)(-7125 1550);
FORCEPROP 2 LAST SIG_NAME PVDD11_S3_P1_IMON2
J 2
(-6560 1560);
DISPLAY 0.489362 (-6560 1560);
WIRE 16 -1 (-7800 2525)(-7800 2650);
WIRE 16 -1 (-7800 2650)(-7450 2650);
WIRE 16 -1 (-7800 2775)(-7800 2650);
WIRE 16 -1 (-7450 2650)(-6850 2650);
WIRE 16 -1 (-7450 2550)(-7450 2650);
WIRE 16 -1 (-6850 2200)(-6850 2650);
WIRE 16 -1 (-6850 2200)(-6475 2200);
WIRE 16 -1 (-6525 3875)(-7125 3875);
FORCEPROP 2 LAST SIG_NAME PVDD11_S3_P1_PWM1
J 2
(-6610 3885);
DISPLAY 0.489362 (-6610 3885);
WIRE 16 -1 (-6525 3975)(-7150 3975);
FORCEPROP 2 LAST SIG_NAME PVDD11_S3_P1_TEMP0
J 2
(-6610 3985);
DISPLAY 0.489362 (-6610 3985);
WIRE 16 -1 (-5625 950)(-5450 950);
WIRE 16 -1 (-5450 950)(-5450 1000);
WIRE 16 -1 (-5450 875)(-5450 950);
WIRE 16 -1 (-5625 1000)(-5450 1000);
WIRE 16 -1 (-5450 1000)(-5450 1050);
WIRE 16 -1 (-5450 1100)(-5450 1050);
WIRE 16 -1 (-5625 1050)(-5450 1050);
WIRE 16 -1 (-5450 1100)(-5625 1100);
WIRE 16 -1 (-5625 1250)(-5100 1250);
FORCEPROP 2 LAST SIG_NAME NC_PVDD11_S3_P1_GL1_2
J 0
(-5485 1260);
DISPLAY 0.489362 (-5485 1260);
FORCEPROP 2 LASTPROP $XRERR UNIQUE?
J 0
(-5070 1250);
DISPLAY 0.638298 (-5070 1250);
PAINT MONO (-5070 1250);
DISPLAY INVISIBLE (-5070 1250);
WIRE 16 -1 (-5625 1200)(-5100 1200);
FORCEPROP 2 LAST SIG_NAME NC_PVDD11_S3_P1_GL2_2
J 0
(-5485 1210);
DISPLAY 0.489362 (-5485 1210);
FORCEPROP 2 LASTPROP $XRERR UNIQUE?
J 0
(-5070 1200);
DISPLAY 0.638298 (-5070 1200);
PAINT MONO (-5070 1200);
DISPLAY INVISIBLE (-5070 1200);
WIRE 16 -1 (-5625 1900)(-4775 1900);
FORCEPROP 2 LAST SIG_NAME SW_PVDD11_S3_P1_BOOT2
J 0
(-5485 1910);
DISPLAY 0.489362 (-5485 1910);
FORCEPROP 2 LASTPROP $XRERR UNIQUE?
J 0
(-5725 1910);
DISPLAY 0.638298 (-5725 1910);
PAINT MONO (-5725 1910);
DISPLAY INVISIBLE (-5725 1910);
WIRE 16 -1 (-4575 1275)(-4575 975);
FORCEPROP 2 LAST SIG_NAME SW_PVDD11_S3_P1_SW2_RC
J 0
(-4535 1110);
DISPLAY 0.489362 (-4535 1110);
FORCEPROP 2 LASTPROP $XRERR UNIQUE?
J 0
(-4775 1110);
DISPLAY 0.638298 (-4775 1110);
PAINT MONO (-4775 1110);
DISPLAY INVISIBLE (-4775 1110);
WIRE 16 -1 (-5625 1300)(-4875 1300);
WIRE 16 -1 (-4875 550)(-4875 1300);
WIRE 16 -1 (-3625 550)(-4875 550);
FORCEPROP 2 LAST SIG_NAME PVDD11_S3_P1_VOS2
J 0
(-5485 1325);
DISPLAY 0.489362 (-5485 1325);
FORCEPROP 2 LASTPROP $XRERR UNIQUE?
J 0
(-5725 1325);
DISPLAY 0.638298 (-5725 1325);
PAINT MONO (-5725 1325);
DISPLAY INVISIBLE (-5725 1325);
WIRE 16 -1 (-5500 2200)(-5500 2150);
WIRE 16 -1 (-5625 2200)(-5500 2200);
WIRE 16 -1 (-5500 2625)(-5500 2200);
WIRE 16 -1 (-5500 2150)(-5625 2150);
WIRE 16 -1 (-5500 2625)(-5350 2625);
WIRE 16 -1 (-5350 2550)(-5350 2625);
WIRE 16 -1 (-5025 2625)(-5350 2625);
WIRE 16 -1 (-4700 2625)(-5025 2625);
WIRE 16 -1 (-5025 2550)(-5025 2625);
WIRE 16 -1 (-4700 2625)(-4400 2625);
WIRE 16 -1 (-4700 2625)(-4700 2550);
WIRE 16 -1 (-4075 2625)(-4400 2625);
WIRE 16 -1 (-4400 2625)(-4400 2550);
WIRE 16 -1 (-3750 2625)(-4075 2625);
WIRE 16 -1 (-4075 2550)(-4075 2625);
WIRE 16 -1 (-3750 2675)(-3750 2625);
WIRE 16 -1 (-3750 2625)(-3750 2550);
WIRE 16 -1 (-5675 3875)(-5450 3875);
WIRE 16 -1 (-5450 3875)(-5450 3925);
WIRE 16 -1 (-5450 3800)(-5450 3875);
WIRE 16 -1 (-5675 3925)(-5450 3925);
WIRE 16 -1 (-5450 3975)(-5450 3925);
WIRE 16 -1 (-5675 3975)(-5450 3975);
WIRE 16 -1 (-5450 4025)(-5450 3975);
WIRE 16 -1 (-5450 4025)(-5675 4025);
WIRE 16 -1 (-5350 2350)(-5350 2225);
WIRE 16 -1 (-5350 2225)(-5025 2225);
WIRE 16 -1 (-5025 2225)(-4700 2225);
WIRE 16 -1 (-5025 2350)(-5025 2225);
WIRE 16 -1 (-4700 2225)(-4400 2225);
WIRE 16 -1 (-4700 2350)(-4700 2225);
WIRE 16 -1 (-4075 2225)(-4400 2225);
WIRE 16 -1 (-4400 2350)(-4400 2225);
WIRE 16 -1 (-3750 2225)(-4075 2225);
WIRE 16 -1 (-4075 2350)(-4075 2225);
WIRE 16 -1 (-3750 2350)(-3750 2225);
WIRE 16 -1 (-3750 2225)(-3750 2200);
WIRE 16 -1 (-4625 4175)(-4625 3850);
FORCEPROP 2 LAST SIG_NAME SW_PVDD11_S3_P1_SW1_RC
J 0
(-4585 3985);
DISPLAY 0.489362 (-4585 3985);
FORCEPROP 2 LASTPROP $XRERR UNIQUE?
J 0
(-4825 3985);
DISPLAY 0.638298 (-4825 3985);
PAINT MONO (-4825 3985);
DISPLAY INVISIBLE (-4825 3985);
WIRE 16 -1 (-8075 4375)(-7900 4375);
WIRE 16 -1 (-6525 4375)(-7900 4375);
FORCEPROP 2 LAST SIG_NAME PVDD11_S3_P1_VCCS
J 2
(-6610 4385);
DISPLAY 0.489362 (-6610 4385);
WIRE 16 -1 (-7900 4300)(-7900 4375);
WIRE 16 -1 (-7075 4975)(-7800 4975);
WIRE 16 -1 (-7075 4975)(-7075 4825);
FORCEPROP 2 LAST SIG_NAME PVDD11_S3_P1_VCC1
J 2
(-6610 4835);
DISPLAY 0.489362 (-6610 4835);
FORCEPROP 2 LASTPROP $XRERR UNIQUE?
J 0
(-6850 4835);
DISPLAY 0.638298 (-6850 4835);
PAINT MONO (-6850 4835);
DISPLAY INVISIBLE (-6850 4835);
WIRE 16 -1 (-7800 5250)(-7800 4975);
WIRE 16 -1 (-7800 4975)(-7800 4900);
WIRE 16 -1 (-7075 4825)(-6525 4825);
WIRE 16 -1 (-7075 4825)(-7075 4625);
WIRE 16 -1 (-7075 4625)(-6525 4625);
WIRE 16 -1 (-6525 4475)(-7175 4475);
FORCEPROP 2 LAST SIG_NAME PVDD11_S3_P1_IMON1
J 2
(-6610 4485);
DISPLAY 0.489362 (-6610 4485);
WIRE 16 -1 (-7125 4175)(-6525 4175);
FORCEPROP 2 LAST SIG_NAME PVDD11_S3_P1_LSET1
J 2
(-6610 4185);
DISPLAY 0.489362 (-6610 4185);
FORCEPROP 2 LASTPROP $XRERR UNIQUE?
J 0
(-6850 4185);
DISPLAY 0.638298 (-6850 4185);
PAINT MONO (-6850 4185);
DISPLAY INVISIBLE (-6850 4185);
WIRE 16 -1 (-6525 4225)(-6975 4225);
FORCEPROP 2 LAST SIG_NAME NC_PVDD11_S3_P1_DNC1
J 2
(-6610 4235);
DISPLAY 0.489362 (-6610 4235);
FORCEPROP 2 LASTPROP $XRERR UNIQUE?
J 0
(-7215 4225);
DISPLAY 0.638298 (-7215 4225);
PAINT MONO (-7215 4225);
DISPLAY INVISIBLE (-7215 4225);
WIRE 16 -1 (-5675 4125)(-5150 4125);
FORCEPROP 2 LAST SIG_NAME NC_PVDD11_S3_P1_GL2_1
J 0
(-5535 4135);
DISPLAY 0.489362 (-5535 4135);
FORCEPROP 2 LASTPROP $XRERR UNIQUE?
J 0
(-5120 4125);
DISPLAY 0.638298 (-5120 4125);
PAINT MONO (-5120 4125);
DISPLAY INVISIBLE (-5120 4125);
WIRE 16 -1 (-5675 4175)(-5150 4175);
FORCEPROP 2 LAST SIG_NAME NC_PVDD11_S3_P1_GL1_1
J 0
(-5535 4185);
DISPLAY 0.489362 (-5535 4185);
FORCEPROP 2 LASTPROP $XRERR UNIQUE?
J 0
(-5120 4175);
DISPLAY 0.638298 (-5120 4175);
PAINT MONO (-5120 4175);
DISPLAY INVISIBLE (-5120 4175);
WIRE 16 -1 (-5575 5125)(-5575 5075);
WIRE 16 -1 (-5575 5550)(-5575 5125);
WIRE 16 -1 (-5675 5125)(-5575 5125);
WIRE 16 -1 (-5575 5075)(-5675 5075);
WIRE 16 -1 (-5575 5550)(-5400 5550);
WIRE 16 -1 (-5400 5550)(-5075 5550);
WIRE 16 -1 (-5400 5475)(-5400 5550);
WIRE 16 -1 (-5075 5550)(-4775 5550);
WIRE 16 -1 (-5075 5475)(-5075 5550);
WIRE 16 -1 (-4400 5550)(-4775 5550);
WIRE 16 -1 (-4775 5475)(-4775 5550);
WIRE 16 -1 (-4400 5550)(-4100 5550);
WIRE 16 -1 (-4400 5550)(-4400 5475);
WIRE 16 -1 (-3900 5550)(-4100 5550);
WIRE 16 -1 (-4100 5550)(-4100 5475);
WIRE 16 -1 (-3900 5550)(-3775 5550);
WIRE 16 -1 (-3900 5600)(-3900 5550);
WIRE 16 -1 (-3375 5550)(-3775 5550);
WIRE 16 -1 (-3775 5475)(-3775 5550);
WIRE 16 -1 (-3050 5550)(-3375 5550);
WIRE 16 -1 (-3375 5475)(-3375 5550);
WIRE 16 -1 (-5400 5275)(-5400 5150);
WIRE 16 -1 (-5400 5150)(-5075 5150);
WIRE 16 -1 (-5075 5150)(-4775 5150);
WIRE 16 -1 (-5075 5275)(-5075 5150);
WIRE 16 -1 (-4400 5150)(-4775 5150);
WIRE 16 -1 (-4775 5275)(-4775 5150);
WIRE 16 -1 (-4400 5150)(-4100 5150);
WIRE 16 -1 (-4400 5275)(-4400 5150);
WIRE 16 -1 (-3900 5150)(-4100 5150);
WIRE 16 -1 (-4100 5275)(-4100 5150);
WIRE 16 -1 (-3775 5150)(-3900 5150);
WIRE 16 -1 (-3900 5150)(-3900 5075);
WIRE 16 -1 (-3775 5150)(-3375 5150);
WIRE 16 -1 (-3775 5275)(-3775 5150);
WIRE 16 -1 (-3375 5275)(-3375 5150);
WIRE 16 -1 (-5675 4825)(-4900 4825);
FORCEPROP 2 LAST SIG_NAME SW_PVDD11_S3_P1_BOOT1
J 0
(-5535 4835);
DISPLAY 0.489362 (-5535 4835);
FORCEPROP 2 LASTPROP $XRERR UNIQUE?
J 0
(-5775 4835);
DISPLAY 0.638298 (-5775 4835);
PAINT MONO (-5775 4835);
DISPLAY INVISIBLE (-5775 4835);
WIRE 16 -1 (-5675 4225)(-4925 4225);
WIRE 16 -1 (-4925 4225)(-4925 3350);
WIRE 16 -1 (-3700 3350)(-4925 3350);
FORCEPROP 2 LAST SIG_NAME PVDD11_S3_P1_VOS1
J 0
(-5535 4250);
DISPLAY 0.489362 (-5535 4250);
FORCEPROP 2 LASTPROP $XRERR UNIQUE?
J 0
(-5775 4250);
DISPLAY 0.638298 (-5775 4250);
PAINT MONO (-5775 4250);
DISPLAY INVISIBLE (-5775 4250);
WIRE 16 -1 (-4575 1900)(-3800 1900);
FORCEPROP 2 LAST SIG_NAME SW_PVDD11_S3_P1_BOOT2_RC
J 2
(-3835 1910);
DISPLAY 0.489362 (-3835 1910);
FORCEPROP 2 LASTPROP $XRERR UNIQUE?
J 0
(-4075 1910);
DISPLAY 0.638298 (-4075 1910);
PAINT MONO (-4075 1910);
DISPLAY INVISIBLE (-4075 1910);
WIRE 16 -1 (-3800 1900)(-3800 1875);
WIRE 16 -1 (-2650 1550)(-2650 550);
WIRE 16 -1 (-2650 1550)(-2400 1550);
WIRE 16 -1 (-2650 1550)(-3200 1550);
WIRE 16 -1 (-2650 550)(-3425 550);
WIRE 16 -1 (-2400 1550)(-1975 1550);
WIRE 16 -1 (-2400 1550)(-2400 1475);
WIRE 16 -1 (-1975 1650)(-1975 1550);
WIRE 16 -1 (-1975 1550)(-1975 1475);
WIRE 16 -1 (-2900 2350)(-2900 2400);
WIRE 16 -1 (-2575 2400)(-2900 2400);
WIRE 16 -1 (-2900 2400)(-2900 2525);
WIRE 16 -1 (-2200 2400)(-2575 2400);
WIRE 16 -1 (-2575 2525)(-2575 2400);
WIRE 16 -1 (-2200 2525)(-2200 2400);
WIRE 16 -1 (-2575 2800)(-2900 2800);
WIRE 16 -1 (-2575 2800)(-2200 2800);
WIRE 16 -1 (-2575 2725)(-2575 2800);
WIRE 16 -1 (-2900 2800)(-2900 2825);
WIRE 16 -1 (-2900 2725)(-2900 2800);
WIRE 16 -1 (-2200 2800)(-2200 2725);
WIRE 16 -1 (-2400 1275)(-2400 1150);
WIRE 16 -1 (-1975 1150)(-2400 1150);
WIRE 16 -1 (-1975 1275)(-1975 1150);
WIRE 16 -1 (-1975 1075)(-1975 1150);
WIRE 16 -1 (-1800 2800)(-1475 2800);
WIRE 16 -1 (-1800 2800)(-1800 2825);
WIRE 16 -1 (-1800 2750)(-1800 2800);
WIRE 16 -1 (-1475 2800)(-1150 2800);
WIRE 16 -1 (-1475 2750)(-1475 2800);
WIRE 16 -1 (-1150 2800)(-825 2800);
WIRE 16 -1 (-1150 2800)(-1150 2750);
WIRE 16 -1 (-825 2800)(-825 2750);
WIRE 16 -1 (-1800 2425)(-1475 2425);
WIRE 16 -1 (-1800 2425)(-1800 2375);
WIRE 16 -1 (-1800 2550)(-1800 2425);
WIRE 16 -1 (-1475 2425)(-1150 2425);
WIRE 16 -1 (-1475 2550)(-1475 2425);
WIRE 16 -1 (-825 2425)(-1150 2425);
WIRE 16 -1 (-1150 2550)(-1150 2425);
WIRE 16 -1 (-825 2550)(-825 2425);
WIRE 16 -1 (-1150 3975)(-1150 4075);
WIRE 16 -1 (-1150 4075)(-1150 4175);
WIRE 16 -1 (-1150 4075)(-1575 4075);
WIRE 16 -1 (-1575 4200)(-1575 4075);
WIRE 16 -1 (-1575 4075)(-2000 4075);
WIRE 16 -1 (-2000 4200)(-2000 4075);
WIRE 16 -1 (-2325 4075)(-2000 4075);
WIRE 16 -1 (-2325 4075)(-2325 4200);
WIRE 16 -1 (-4700 4825)(-3900 4825);
FORCEPROP 2 LAST SIG_NAME SW_PVDD11_S3_P1_BOOT1_RC
J 2
(-3935 4835);
DISPLAY 0.489362 (-3935 4835);
FORCEPROP 2 LASTPROP $XRERR UNIQUE?
J 0
(-4175 4835);
DISPLAY 0.638298 (-4175 4835);
PAINT MONO (-4175 4835);
DISPLAY INVISIBLE (-4175 4835);
WIRE 16 -1 (-3900 4825)(-3900 4800);
WIRE 16 -1 (-2675 5575)(-2675 5550);
WIRE 16 -1 (-2675 5550)(-2850 5550);
DOT 1 (-5500 2200);
DOT 1 (-4400 5150);
DOT 1 (-4100 5150);
DOT 1 (-3900 5150);
DOT 1 (-3775 5150);
DOT 1 (-7850 1450);
DOT 1 (-7075 1900);
DOT 1 (-7800 2050);
DOT 1 (-7800 2650);
DOT 1 (-7450 2650);
DOT 1 (-5450 1000);
DOT 1 (-5450 950);
DOT 1 (-5450 1050);
DOT 1 (-5350 2625);
DOT 1 (-5450 3925);
DOT 1 (-5450 3875);
DOT 1 (-5450 3975);
DOT 1 (-5025 2225);
DOT 1 (-4700 2225);
DOT 1 (-5025 2625);
DOT 1 (-4700 2625);
DOT 1 (-4400 2225);
DOT 1 (-4400 2625);
DOT 1 (-7900 4375);
DOT 1 (-7800 4975);
DOT 1 (-8100 5575);
DOT 1 (-7800 5575);
DOT 1 (-7625 5575);
DOT 1 (-7450 5575);
DOT 1 (-7075 4825);
DOT 1 (-5575 5125);
DOT 1 (-5400 5550);
DOT 1 (-4625 4475);
DOT 1 (-5075 5150);
DOT 1 (-5075 5550);
DOT 1 (-4775 5150);
DOT 1 (-4775 5550);
DOT 1 (-4400 5550);
DOT 1 (-4100 5550);
DOT 1 (-2650 1550);
DOT 1 (-2400 1550);
DOT 1 (-3750 2225);
DOT 1 (-4075 2625);
DOT 1 (-3750 2625);
DOT 1 (-1975 1150);
DOT 1 (-1975 1550);
DOT 1 (-2000 4075);
DOT 1 (-1575 4075);
DOT 1 (-1150 4075);
DOT 1 (-3900 5550);
DOT 1 (-3375 5550);
DOT 1 (-2575 4475);
DOT 1 (-2325 4475);
DOT 1 (-2000 4475);
DOT 1 (-1575 4475);
DOT 1 (-1150 4475);
DOT 1 (-3775 5550);
DOT 1 (-2900 2400);
DOT 1 (-2575 2400);
DOT 1 (-1475 2425);
DOT 1 (-1800 2800);
DOT 1 (-1475 2800);
DOT 1 (-1150 2800);
DOT 1 (-1150 2425);
DOT 1 (-2575 2800);
DOT 1 (-2900 2800);
DOT 1 (-4075 2225);
DOT 1 (-1800 2425);
DOT 1 (-4575 1550);
FORCENOTE
PR328,PR329 = CS00002JB38
(-9350 275) 0;
DISPLAY LEFT (-9350 275);
DISPLAY 1.021277 (-9350 275);
PAINT WHITE (-9350 275);
FORCENOTE
PR330,PR331 = CS00002JB38
(-9350 500) 0;
DISPLAY LEFT (-9350 500);
DISPLAY 1.021277 (-9350 500);
PAINT WHITE (-9350 500);
FORCENOTE
PC503_1,PC504_2 = EMPTY
(-9350 350) 0;
DISPLAY LEFT (-9350 350);
DISPLAY 1.021277 (-9350 350);
PAINT WHITE (-9350 350);
FORCENOTE
PR332,PR333 = EMPTY
(-9350 425) 0;
DISPLAY LEFT (-9350 425);
DISPLAY 1.021277 (-9350 425);
PAINT WHITE (-9350 425);
FORCENOTE
PR394,PR330,PR331=CS00002JB38
(-9350 -75) 0;
DISPLAY LEFT (-9350 -75);
DISPLAY 1.021277 (-9350 -75);
PAINT WHITE (-9350 -75);
FORCENOTE
PR387,PC503_1,PC504_2,PR332,PR333=EMPTY
(-9350 0) 0;
DISPLAY LEFT (-9350 0);
DISPLAY 1.021277 (-9350 0);
PAINT WHITE (-9350 0);
FORCENOTE
PU44,PU45 =AL087000A02/MP87000GMJTH-C06A-Z
(-9350 75) 0;
DISPLAY LEFT (-9350 75);
DISPLAY 1.021277 (-9350 75);
PAINT WHITE (-9350 75);
FORCENOTE
3RD SOURCE:MPS BOM
(-9350 150) 0;
DISPLAY LEFT (-9350 150);
DISPLAY 1.021277 (-9350 150);
PAINT WHITE (-9350 150);
FORCENOTE
MAIN SOURCE:RENESAS BOM
(-9350 875) 0;
DISPLAY LEFT (-9350 875);
DISPLAY 1.021277 (-9350 875);
PAINT WHITE (-9350 875);
FORCENOTE
PVDD11_S3_P1_PHASE1
(-6650 5875) 0;
DISPLAY LEFT (-6650 5875);
DISPLAY 1.595745 (-6650 5875);
PAINT WHITE (-6650 5875);
FORCENOTE
5.0*5.8
(-3475 5000) 0;
DISPLAY LEFT (-3475 5000);
DISPLAY 0.638298 (-3475 5000);
PAINT WHITE (-3475 5000);
FORCENOTE
PVDD11_S3_P1_PHASE2
(-6600 2950) 0;
DISPLAY LEFT (-6600 2950);
DISPLAY 1.595745 (-6600 2950);
PAINT WHITE (-6600 2950);
FORCENOTE
5.0*5.8
(-1625 2325) 0;
DISPLAY LEFT (-1625 2325);
DISPLAY 0.638298 (-1625 2325);
PAINT WHITE (-1625 2325);
FORCENOTE
PG2289.101HLT
(-3125 5475) 0;
DISPLAY LEFT (-3125 5475);
DISPLAY 0.638298 (-3125 5475);
PAINT WHITE (-3125 5475);
FORCENOTE
ISAT:13A@100C
(-3125 5425) 0;
DISPLAY LEFT (-3125 5425);
DISPLAY 0.638298 (-3125 5425);
PAINT WHITE (-3125 5425);
FORCENOTE
4.5*4.7*4.5
(-3125 5375) 0;
DISPLAY LEFT (-3125 5375);
DISPLAY 0.638298 (-3125 5375);
PAINT WHITE (-3125 5375);
FORCENOTE
ESR=26M OHM
(-3475 5100) 0;
DISPLAY LEFT (-3475 5100);
DISPLAY 0.638298 (-3475 5100);
PAINT WHITE (-3475 5100);
FORCENOTE
IRIPPLE:3A
(-3475 5050) 0;
DISPLAY LEFT (-3475 5050);
DISPLAY 0.638298 (-3475 5050);
PAINT WHITE (-3475 5050);
FORCENOTE
2ND=CV+10G0MZ04
(-3125 5275) 0;
DISPLAY LEFT (-3125 5275);
DISPLAY 0.638298 (-3125 5275);
PAINT WHITE (-3125 5275);
FORCENOTE
3RD=CV+10G0MZ08
(-3125 5225) 0;
DISPLAY LEFT (-3125 5225);
DISPLAY 0.638298 (-3125 5225);
PAINT WHITE (-3125 5225);
FORCENOTE
DCR:0.105M OHM
(-3125 5325) 0;
DISPLAY LEFT (-3125 5325);
DISPLAY 0.638298 (-3125 5325);
PAINT WHITE (-3125 5325);
FORCENOTE
DCR=0.125M OHM
(-3475 1150) 0;
DISPLAY LEFT (-3475 1150);
DISPLAY 0.638298 (-3475 1150);
PAINT WHITE (-3475 1150);
FORCENOTE
2ND=CV+12^0TZ02
(-3475 1100) 0;
DISPLAY LEFT (-3475 1100);
DISPLAY 0.638298 (-3475 1100);
PAINT WHITE (-3475 1100);
FORCENOTE
PGL6054.121AHLT
(-3475 1300) 0;
DISPLAY LEFT (-3475 1300);
DISPLAY 0.638298 (-3475 1300);
PAINT WHITE (-3475 1300);
FORCENOTE
10.0*6.0*12.0
(-3475 1200) 0;
DISPLAY LEFT (-3475 1200);
DISPLAY 0.638298 (-3475 1200);
PAINT WHITE (-3475 1200);
FORCENOTE
ISAT:88A@100C
(-3475 1250) 0;
DISPLAY LEFT (-3475 1250);
DISPLAY 0.638298 (-3475 1250);
PAINT WHITE (-3475 1250);
FORCENOTE
3RD=CV+12^0TZ01
(-3475 1050) 0;
DISPLAY LEFT (-3475 1050);
DISPLAY 0.638298 (-3475 1050);
PAINT WHITE (-3475 1050);
FORCENOTE
7.3*4.3*1.9
(-2825 2275) 0;
DISPLAY LEFT (-2825 2275);
DISPLAY 0.638298 (-2825 2275);
PAINT WHITE (-2825 2275);
FORCENOTE
ESR=9M OHM
(-2825 2325) 0;
DISPLAY LEFT (-2825 2325);
DISPLAY 0.638298 (-2825 2325);
PAINT WHITE (-2825 2325);
FORCENOTE
BOM NOTE
(-9350 975) 0;
DISPLAY LEFT (-9350 975);
DISPLAY 1.021277 (-9350 975);
PAINT WHITE (-9350 975);
FORCENOTE
PU44,PU45 =AL099390004/ISL99390FRZ-TR5935
(-9350 800) 0;
DISPLAY LEFT (-9350 800);
DISPLAY 1.021277 (-9350 800);
PAINT WHITE (-9350 800);
FORCENOTE
PU44,PU45 = AL021590000/TDA21590
(-9350 575) 0;
DISPLAY LEFT (-9350 575);
DISPLAY 1.021277 (-9350 575);
PAINT WHITE (-9350 575);
FORCENOTE
2ND SOURCE:INFENEON BOM
(-9350 650) 0;
DISPLAY LEFT (-9350 650);
DISPLAY 1.021277 (-9350 650);
PAINT WHITE (-9350 650);
FORCENOTE
ESR=10M OHM
(-1625 2375) 0;
DISPLAY LEFT (-1625 2375);
DISPLAY 0.638298 (-1625 2375);
PAINT WHITE (-1625 2375);
FORCENOTE
PGL6054.121AHLT
(-3525 4225) 0;
DISPLAY LEFT (-3525 4225);
DISPLAY 0.638298 (-3525 4225);
PAINT WHITE (-3525 4225);
FORCENOTE
ISAT:88A@100C
(-3525 4175) 0;
DISPLAY LEFT (-3525 4175);
DISPLAY 0.638298 (-3525 4175);
PAINT WHITE (-3525 4175);
FORCENOTE
10.0*6.0*12.0
(-3525 4125) 0;
DISPLAY LEFT (-3525 4125);
DISPLAY 0.638298 (-3525 4125);
PAINT WHITE (-3525 4125);
FORCENOTE
2ND=CV+12^0TZ02
(-3525 4025) 0;
DISPLAY LEFT (-3525 4025);
DISPLAY 0.638298 (-3525 4025);
PAINT WHITE (-3525 4025);
FORCENOTE
3RD=CV+12^0TZ01
(-3525 3975) 0;
DISPLAY LEFT (-3525 3975);
DISPLAY 0.638298 (-3525 3975);
PAINT WHITE (-3525 3975);
FORCENOTE
DCR=0.125M OHM
(-3525 4075) 0;
DISPLAY LEFT (-3525 4075);
DISPLAY 0.638298 (-3525 4075);
PAINT WHITE (-3525 4075);
QUIT
